FILE_TYPE = MACRO_DRAWING;
SET COLOR_WIRE YELLOW;
SET COLOR_PROP MONO;
SET COLOR_DOT WHITE;
SET COLOR_ARC YELLOW;
SET COLOR_BODY GREEN;
SET COLOR_NOTE MONO;
SET PROP_DISPLAY VALUE;
SET PAGE_NUMBER P75;
FORCEADD GND..1
(-5675 400);
FORCEPROP 3 LASTPIN (-5675 450) SIG_NAME GND\g
J 0
(-5665 460);
DISPLAY 0.659574 (-5665 460);
PAINT MONO (-5665 460);
DISPLAY INVISIBLE (-5665 460);
FORCEPROP 1 LAST VOLTAGE 0.0V
J 0
(-5720 357);
DISPLAY 0.340426 (-5720 357);
PAINT SKYBLUE (-5720 357);
DISPLAY INVISIBLE (-5720 357);
FORCEPROP 2 LAST CDS_LIB mstr_symbols
J 0
(-5675 400);
PAINT ORANGE (-5675 400);
DISPLAY INVISIBLE (-5675 400);
FORCEPROP 1 LAST SIZE 1B
J 0
(-5600 350);
DISPLAY 1.170213 (-5600 350);
PAINT AQUA (-5600 350);
DISPLAY INVISIBLE (-5600 350);
FORCEPROP 1 LAST BODY_TYPE PLUMBING
J 0
(-5720 357);
DISPLAY 0.340426 (-5720 357);
PAINT GREEN (-5720 357);
DISPLAY INVISIBLE (-5720 357);
FORCEPROP 1 LAST PATH I10
J 0
(-5600 400);
DISPLAY 0.872340 (-5600 400);
PAINT AQUA (-5600 400);
DISPLAY INVISIBLE (-5600 400);
FORCEPROP 1 LAST HDL_POWER GND
J 0
(-5675 550);
DISPLAY 1.170213 (-5675 550);
PAINT GREEN (-5675 550);
DISPLAY INVISIBLE (-5675 550);
FORCEADD GND..1
(-3775 400);
FORCEPROP 3 LASTPIN (-3775 450) SIG_NAME GND\g
J 0
(-3765 460);
DISPLAY 0.659574 (-3765 460);
PAINT MONO (-3765 460);
DISPLAY INVISIBLE (-3765 460);
FORCEPROP 1 LAST VOLTAGE 0.0V
J 0
(-3820 357);
DISPLAY 0.340426 (-3820 357);
PAINT SKYBLUE (-3820 357);
DISPLAY INVISIBLE (-3820 357);
FORCEPROP 1 LAST SIZE 1B
J 0
(-3700 350);
DISPLAY 1.170213 (-3700 350);
PAINT AQUA (-3700 350);
DISPLAY INVISIBLE (-3700 350);
FORCEPROP 2 LAST CDS_LIB mstr_symbols
J 0
(-3775 400);
PAINT ORANGE (-3775 400);
DISPLAY INVISIBLE (-3775 400);
FORCEPROP 1 LAST BODY_TYPE PLUMBING
J 0
(-3820 357);
DISPLAY 0.340426 (-3820 357);
PAINT GREEN (-3820 357);
DISPLAY INVISIBLE (-3820 357);
FORCEPROP 1 LAST PATH I11
J 0
(-3700 400);
DISPLAY 0.872340 (-3700 400);
PAINT AQUA (-3700 400);
DISPLAY INVISIBLE (-3700 400);
FORCEPROP 1 LAST HDL_POWER GND
J 0
(-3775 550);
DISPLAY 1.170213 (-3775 550);
PAINT GREEN (-3775 550);
DISPLAY INVISIBLE (-3775 550);
FORCEADD GND..1
(-1975 400);
FORCEPROP 3 LASTPIN (-1975 450) SIG_NAME GND\g
J 0
(-1965 460);
DISPLAY 0.659574 (-1965 460);
PAINT MONO (-1965 460);
DISPLAY INVISIBLE (-1965 460);
FORCEPROP 1 LAST VOLTAGE 0.0V
J 0
(-2020 357);
DISPLAY 0.340426 (-2020 357);
PAINT SKYBLUE (-2020 357);
DISPLAY INVISIBLE (-2020 357);
FORCEPROP 1 LAST SIZE 1B
J 0
(-1900 350);
DISPLAY 1.170213 (-1900 350);
PAINT AQUA (-1900 350);
DISPLAY INVISIBLE (-1900 350);
FORCEPROP 2 LAST CDS_LIB mstr_symbols
J 0
(-1975 400);
PAINT ORANGE (-1975 400);
DISPLAY INVISIBLE (-1975 400);
FORCEPROP 1 LAST BODY_TYPE PLUMBING
J 0
(-2020 357);
DISPLAY 0.340426 (-2020 357);
PAINT GREEN (-2020 357);
DISPLAY INVISIBLE (-2020 357);
FORCEPROP 1 LAST PATH I12
J 0
(-1900 400);
DISPLAY 0.872340 (-1900 400);
PAINT AQUA (-1900 400);
DISPLAY INVISIBLE (-1900 400);
FORCEPROP 1 LAST HDL_POWER GND
J 0
(-1975 550);
DISPLAY 1.170213 (-1975 550);
PAINT GREEN (-1975 550);
DISPLAY INVISIBLE (-1975 550);
FORCEADD GND..1
(-2275 400);
FORCEPROP 3 LASTPIN (-2275 450) SIG_NAME GND\g
J 0
(-2265 460);
DISPLAY 0.659574 (-2265 460);
PAINT MONO (-2265 460);
DISPLAY INVISIBLE (-2265 460);
FORCEPROP 1 LAST VOLTAGE 0.0V
J 0
(-2320 357);
DISPLAY 0.340426 (-2320 357);
PAINT SKYBLUE (-2320 357);
DISPLAY INVISIBLE (-2320 357);
FORCEPROP 2 LAST CDS_LIB mstr_symbols
J 0
(-2275 400);
PAINT ORANGE (-2275 400);
DISPLAY INVISIBLE (-2275 400);
FORCEPROP 1 LAST SIZE 1B
J 0
(-2200 350);
DISPLAY 1.170213 (-2200 350);
PAINT AQUA (-2200 350);
DISPLAY INVISIBLE (-2200 350);
FORCEPROP 1 LAST BODY_TYPE PLUMBING
J 0
(-2320 357);
DISPLAY 0.340426 (-2320 357);
PAINT GREEN (-2320 357);
DISPLAY INVISIBLE (-2320 357);
FORCEPROP 1 LAST PATH I13
J 0
(-2200 400);
DISPLAY 0.872340 (-2200 400);
PAINT AQUA (-2200 400);
DISPLAY INVISIBLE (-2200 400);
FORCEPROP 1 LAST HDL_POWER GND
J 0
(-2275 550);
DISPLAY 1.170213 (-2275 550);
PAINT GREEN (-2275 550);
DISPLAY INVISIBLE (-2275 550);
FORCEADD GND..1
(-4150 400);
FORCEPROP 3 LASTPIN (-4150 450) SIG_NAME GND\g
J 0
(-4140 460);
DISPLAY 0.659574 (-4140 460);
PAINT MONO (-4140 460);
DISPLAY INVISIBLE (-4140 460);
FORCEPROP 1 LAST VOLTAGE 0.0V
J 0
(-4195 357);
DISPLAY 0.340426 (-4195 357);
PAINT SKYBLUE (-4195 357);
DISPLAY INVISIBLE (-4195 357);
FORCEPROP 2 LAST CDS_LIB mstr_symbols
J 0
(-4150 400);
PAINT ORANGE (-4150 400);
DISPLAY INVISIBLE (-4150 400);
FORCEPROP 1 LAST SIZE 1B
J 0
(-4075 350);
DISPLAY 1.170213 (-4075 350);
PAINT AQUA (-4075 350);
DISPLAY INVISIBLE (-4075 350);
FORCEPROP 1 LAST BODY_TYPE PLUMBING
J 0
(-4195 357);
DISPLAY 0.340426 (-4195 357);
PAINT GREEN (-4195 357);
DISPLAY INVISIBLE (-4195 357);
FORCEPROP 1 LAST PATH I14
J 0
(-4075 400);
DISPLAY 0.872340 (-4075 400);
PAINT AQUA (-4075 400);
DISPLAY INVISIBLE (-4075 400);
FORCEPROP 1 LAST HDL_POWER GND
J 0
(-4150 550);
DISPLAY 1.170213 (-4150 550);
PAINT GREEN (-4150 550);
DISPLAY INVISIBLE (-4150 550);
FORCEADD GND..1
(-5950 400);
FORCEPROP 3 LASTPIN (-5950 450) SIG_NAME GND\g
J 0
(-5940 460);
DISPLAY 0.659574 (-5940 460);
PAINT MONO (-5940 460);
DISPLAY INVISIBLE (-5940 460);
FORCEPROP 1 LAST VOLTAGE 0.0V
J 0
(-5995 357);
DISPLAY 0.340426 (-5995 357);
PAINT SKYBLUE (-5995 357);
DISPLAY INVISIBLE (-5995 357);
FORCEPROP 2 LAST CDS_LIB mstr_symbols
J 0
(-5950 400);
PAINT ORANGE (-5950 400);
DISPLAY INVISIBLE (-5950 400);
FORCEPROP 1 LAST SIZE 1B
J 0
(-5875 350);
DISPLAY 1.170213 (-5875 350);
PAINT AQUA (-5875 350);
DISPLAY INVISIBLE (-5875 350);
FORCEPROP 1 LAST BODY_TYPE PLUMBING
J 0
(-5995 357);
DISPLAY 0.340426 (-5995 357);
PAINT GREEN (-5995 357);
DISPLAY INVISIBLE (-5995 357);
FORCEPROP 1 LAST PATH I15
J 0
(-5875 400);
DISPLAY 0.872340 (-5875 400);
PAINT AQUA (-5875 400);
DISPLAY INVISIBLE (-5875 400);
FORCEPROP 1 LAST HDL_POWER GND
J 0
(-5950 550);
DISPLAY 1.170213 (-5950 550);
PAINT GREEN (-5950 550);
DISPLAY INVISIBLE (-5950 550);
FORCEADD GND..1
(-450 1700);
FORCEPROP 3 LASTPIN (-450 1750) SIG_NAME GND\g
J 0
(-440 1760);
DISPLAY 0.659574 (-440 1760);
PAINT MONO (-440 1760);
DISPLAY INVISIBLE (-440 1760);
FORCEPROP 1 LAST VOLTAGE 0.0V
J 0
(-495 1657);
DISPLAY 0.340426 (-495 1657);
PAINT SKYBLUE (-495 1657);
DISPLAY INVISIBLE (-495 1657);
FORCEPROP 2 LAST CDS_LIB mstr_symbols
J 0
(-450 1700);
PAINT ORANGE (-450 1700);
DISPLAY INVISIBLE (-450 1700);
FORCEPROP 1 LAST SIZE 1B
J 0
(-375 1650);
DISPLAY 1.170213 (-375 1650);
PAINT AQUA (-375 1650);
DISPLAY INVISIBLE (-375 1650);
FORCEPROP 1 LAST BODY_TYPE PLUMBING
J 0
(-495 1657);
DISPLAY 0.340426 (-495 1657);
PAINT GREEN (-495 1657);
DISPLAY INVISIBLE (-495 1657);
FORCEPROP 1 LAST PATH I16
J 0
(-375 1700);
DISPLAY 0.872340 (-375 1700);
PAINT AQUA (-375 1700);
DISPLAY INVISIBLE (-375 1700);
FORCEPROP 1 LAST HDL_POWER GND
J 0
(-450 1850);
DISPLAY 1.170213 (-450 1850);
PAINT GREEN (-450 1850);
DISPLAY INVISIBLE (-450 1850);
FORCEADD SKX_EXT_B..27
(-6725 2525);
FORCEPROP 1 LAST LOCATION U2D1
J 0
(-7275 4775);
DISPLAY 0.617021 (-7275 4775);
PAINT AQUA (-7275 4775);
FORCEPROP 1 LAST PART_NUMBER TBD
J 0
(-7275 375);
DISPLAY 0.617021 (-7275 375);
PAINT BLUE (-7275 375);
FORCEPROP 1 LAST MATERIAL IC
J 0
(-7275 4725);
DISPLAY 0.617021 (-7275 4725);
PAINT SKYBLUE (-7275 4725);
FORCEPROP 2 LASTPIN (-7325 4475) $PN BG76
J 2
(-7335 4485);
DISPLAY 0.617021 (-7335 4485);
PAINT ORANGE (-7335 4485);
FORCEPROP 2 LASTPIN (-7325 4425) $PN BG78
J 2
(-7335 4435);
DISPLAY 0.617021 (-7335 4435);
PAINT ORANGE (-7335 4435);
FORCEPROP 2 LASTPIN (-7325 4375) $PN BG80
J 2
(-7335 4385);
DISPLAY 0.617021 (-7335 4385);
PAINT ORANGE (-7335 4385);
FORCEPROP 2 LASTPIN (-7325 4325) $PN BG82
J 2
(-7335 4335);
DISPLAY 0.617021 (-7335 4335);
PAINT ORANGE (-7335 4335);
FORCEPROP 2 LASTPIN (-7325 4275) $PN BH7
J 2
(-7335 4285);
DISPLAY 0.617021 (-7335 4285);
PAINT ORANGE (-7335 4285);
FORCEPROP 2 LASTPIN (-7325 4225) $PN BH9
J 2
(-7335 4235);
DISPLAY 0.617021 (-7335 4235);
PAINT ORANGE (-7335 4235);
FORCEPROP 2 LASTPIN (-7325 4175) $PN BH11
J 2
(-7335 4185);
DISPLAY 0.617021 (-7335 4185);
PAINT ORANGE (-7335 4185);
FORCEPROP 2 LASTPIN (-7325 4125) $PN BH15
J 2
(-7335 4135);
DISPLAY 0.617021 (-7335 4135);
PAINT ORANGE (-7335 4135);
FORCEPROP 2 LASTPIN (-7325 4075) $PN BH21
J 2
(-7335 4085);
DISPLAY 0.617021 (-7335 4085);
PAINT ORANGE (-7335 4085);
FORCEPROP 2 LASTPIN (-7325 4025) $PN BJ4
J 2
(-7335 4035);
DISPLAY 0.617021 (-7335 4035);
PAINT ORANGE (-7335 4035);
FORCEPROP 2 LASTPIN (-7325 3975) $PN BJ6
J 2
(-7335 3985);
DISPLAY 0.617021 (-7335 3985);
PAINT ORANGE (-7335 3985);
FORCEPROP 2 LASTPIN (-7325 3925) $PN BK3
J 2
(-7335 3935);
DISPLAY 0.617021 (-7335 3935);
PAINT ORANGE (-7335 3935);
FORCEPROP 2 LASTPIN (-7325 3875) $PN BK7
J 2
(-7335 3885);
DISPLAY 0.617021 (-7335 3885);
PAINT ORANGE (-7335 3885);
FORCEPROP 2 LASTPIN (-7325 3825) $PN BK11
J 2
(-7335 3835);
DISPLAY 0.617021 (-7335 3835);
PAINT ORANGE (-7335 3835);
FORCEPROP 2 LASTPIN (-7325 3775) $PN BK19
J 2
(-7335 3785);
DISPLAY 0.617021 (-7335 3785);
PAINT ORANGE (-7335 3785);
FORCEPROP 2 LASTPIN (-7325 3725) $PN BL6
J 2
(-7335 3735);
DISPLAY 0.617021 (-7335 3735);
PAINT ORANGE (-7335 3735);
FORCEPROP 2 LASTPIN (-7325 3675) $PN BL10
J 2
(-7335 3685);
DISPLAY 0.617021 (-7335 3685);
PAINT ORANGE (-7335 3685);
FORCEPROP 2 LASTPIN (-7325 3625) $PN BL12
J 2
(-7335 3635);
DISPLAY 0.617021 (-7335 3635);
PAINT ORANGE (-7335 3635);
FORCEPROP 2 LASTPIN (-7325 3575) $PN P61
J 2
(-7335 3585);
DISPLAY 0.617021 (-7335 3585);
PAINT ORANGE (-7335 3585);
FORCEPROP 2 LASTPIN (-7325 3525) $PN BL22
J 2
(-7335 3535);
DISPLAY 0.617021 (-7335 3535);
PAINT ORANGE (-7335 3535);
FORCEPROP 2 LASTPIN (-7325 3475) $PN BL24
J 2
(-7335 3485);
DISPLAY 0.617021 (-7335 3485);
PAINT ORANGE (-7335 3485);
FORCEPROP 2 LASTPIN (-7325 3425) $PN BL64
J 2
(-7335 3435);
DISPLAY 0.617021 (-7335 3435);
PAINT ORANGE (-7335 3435);
FORCEPROP 2 LASTPIN (-7325 3375) $PN BL66
J 2
(-7335 3385);
DISPLAY 0.617021 (-7335 3385);
PAINT ORANGE (-7335 3385);
FORCEPROP 2 LASTPIN (-7325 3325) $PN BL68
J 2
(-7335 3335);
DISPLAY 0.617021 (-7335 3335);
PAINT ORANGE (-7335 3335);
FORCEPROP 2 LASTPIN (-7325 3275) $PN BL70
J 2
(-7335 3285);
DISPLAY 0.617021 (-7335 3285);
PAINT ORANGE (-7335 3285);
FORCEPROP 2 LASTPIN (-7325 3225) $PN BL72
J 2
(-7335 3235);
DISPLAY 0.617021 (-7335 3235);
PAINT ORANGE (-7335 3235);
FORCEPROP 2 LASTPIN (-7325 3175) $PN BL74
J 2
(-7335 3185);
DISPLAY 0.617021 (-7335 3185);
PAINT ORANGE (-7335 3185);
FORCEPROP 2 LASTPIN (-7325 3125) $PN BL76
J 2
(-7335 3135);
DISPLAY 0.617021 (-7335 3135);
PAINT ORANGE (-7335 3135);
FORCEPROP 2 LASTPIN (-7325 3075) $PN BL78
J 2
(-7335 3085);
DISPLAY 0.617021 (-7335 3085);
PAINT ORANGE (-7335 3085);
FORCEPROP 2 LASTPIN (-7325 3025) $PN BL80
J 2
(-7335 3035);
DISPLAY 0.617021 (-7335 3035);
PAINT ORANGE (-7335 3035);
FORCEPROP 2 LASTPIN (-7325 2975) $PN BL82
J 2
(-7335 2985);
DISPLAY 0.617021 (-7335 2985);
PAINT ORANGE (-7335 2985);
FORCEPROP 2 LASTPIN (-7325 2925) $PN BM9
J 2
(-7335 2935);
DISPLAY 0.617021 (-7335 2935);
PAINT ORANGE (-7335 2935);
FORCEPROP 2 LASTPIN (-7325 2875) $PN BM13
J 2
(-7335 2885);
DISPLAY 0.617021 (-7335 2885);
PAINT ORANGE (-7335 2885);
FORCEPROP 2 LASTPIN (-7325 2825) $PN BM15
J 2
(-7335 2835);
DISPLAY 0.617021 (-7335 2835);
PAINT ORANGE (-7335 2835);
FORCEPROP 2 LASTPIN (-7325 2775) $PN P59
J 2
(-7335 2785);
DISPLAY 0.617021 (-7335 2785);
PAINT ORANGE (-7335 2785);
FORCEPROP 2 LASTPIN (-7325 2725) $PN BM25
J 2
(-7335 2735);
DISPLAY 0.617021 (-7335 2735);
PAINT ORANGE (-7335 2735);
FORCEPROP 2 LASTPIN (-7325 2675) $PN BN6
J 2
(-7335 2685);
DISPLAY 0.617021 (-7335 2685);
PAINT ORANGE (-7335 2685);
FORCEPROP 2 LASTPIN (-7325 2625) $PN BN10
J 2
(-7335 2635);
DISPLAY 0.617021 (-7335 2635);
PAINT ORANGE (-7335 2635);
FORCEPROP 2 LASTPIN (-7325 2575) $PN BN20
J 2
(-7335 2585);
DISPLAY 0.617021 (-7335 2585);
PAINT ORANGE (-7335 2585);
FORCEPROP 2 LASTPIN (-7325 2525) $PN BN26
J 2
(-7335 2535);
DISPLAY 0.617021 (-7335 2535);
PAINT ORANGE (-7335 2535);
FORCEPROP 2 LASTPIN (-7325 2475) $PN BP3
J 2
(-7335 2485);
DISPLAY 0.617021 (-7335 2485);
PAINT ORANGE (-7335 2485);
FORCEPROP 2 LASTPIN (-7325 2425) $PN BP27
J 2
(-7335 2435);
DISPLAY 0.617021 (-7335 2435);
PAINT ORANGE (-7335 2435);
FORCEPROP 2 LASTPIN (-7325 2375) $PN BR6
J 2
(-7335 2385);
DISPLAY 0.617021 (-7335 2385);
PAINT ORANGE (-7335 2385);
FORCEPROP 2 LASTPIN (-7325 2325) $PN BR10
J 2
(-7335 2335);
DISPLAY 0.617021 (-7335 2335);
PAINT ORANGE (-7335 2335);
FORCEPROP 2 LASTPIN (-7325 2275) $PN BR16
J 2
(-7335 2285);
DISPLAY 0.617021 (-7335 2285);
PAINT ORANGE (-7335 2285);
FORCEPROP 2 LASTPIN (-7325 2225) $PN P57
J 2
(-7335 2235);
DISPLAY 0.617021 (-7335 2235);
PAINT ORANGE (-7335 2235);
FORCEPROP 2 LASTPIN (-7325 2175) $PN BR64
J 2
(-7335 2185);
DISPLAY 0.617021 (-7335 2185);
PAINT ORANGE (-7335 2185);
FORCEPROP 2 LASTPIN (-7325 2125) $PN BR66
J 2
(-7335 2135);
DISPLAY 0.617021 (-7335 2135);
PAINT ORANGE (-7335 2135);
FORCEPROP 2 LASTPIN (-7325 2075) $PN BR68
J 2
(-7335 2085);
DISPLAY 0.617021 (-7335 2085);
PAINT ORANGE (-7335 2085);
FORCEPROP 2 LASTPIN (-7325 2025) $PN BR70
J 2
(-7335 2035);
DISPLAY 0.617021 (-7335 2035);
PAINT ORANGE (-7335 2035);
FORCEPROP 2 LASTPIN (-7325 1975) $PN BR72
J 2
(-7335 1985);
DISPLAY 0.617021 (-7335 1985);
PAINT ORANGE (-7335 1985);
FORCEPROP 2 LASTPIN (-7325 1925) $PN BR74
J 2
(-7335 1935);
DISPLAY 0.617021 (-7335 1935);
PAINT ORANGE (-7335 1935);
FORCEPROP 2 LASTPIN (-7325 1875) $PN BR76
J 2
(-7335 1885);
DISPLAY 0.617021 (-7335 1885);
PAINT ORANGE (-7335 1885);
FORCEPROP 2 LASTPIN (-7325 1825) $PN BR78
J 2
(-7335 1835);
DISPLAY 0.617021 (-7335 1835);
PAINT ORANGE (-7335 1835);
FORCEPROP 2 LASTPIN (-7325 1775) $PN BR80
J 2
(-7335 1785);
DISPLAY 0.617021 (-7335 1785);
PAINT ORANGE (-7335 1785);
FORCEPROP 2 LASTPIN (-7325 1725) $PN BR82
J 2
(-7335 1735);
DISPLAY 0.617021 (-7335 1735);
PAINT ORANGE (-7335 1735);
FORCEPROP 2 LASTPIN (-7325 1675) $PN BT3
J 2
(-7335 1685);
DISPLAY 0.617021 (-7335 1685);
PAINT ORANGE (-7335 1685);
FORCEPROP 2 LASTPIN (-7325 1625) $PN BT5
J 2
(-7335 1635);
DISPLAY 0.617021 (-7335 1635);
PAINT ORANGE (-7335 1635);
FORCEPROP 2 LASTPIN (-7325 1575) $PN BT21
J 2
(-7335 1585);
DISPLAY 0.617021 (-7335 1585);
PAINT ORANGE (-7335 1585);
FORCEPROP 2 LASTPIN (-7325 1525) $PN BT23
J 2
(-7335 1535);
DISPLAY 0.617021 (-7335 1535);
PAINT ORANGE (-7335 1535);
FORCEPROP 2 LASTPIN (-7325 1475) $PN BT25
J 2
(-7335 1485);
DISPLAY 0.617021 (-7335 1485);
PAINT ORANGE (-7335 1485);
FORCEPROP 2 LASTPIN (-7325 1425) $PN BU8
J 2
(-7335 1435);
DISPLAY 0.617021 (-7335 1435);
PAINT ORANGE (-7335 1435);
FORCEPROP 2 LASTPIN (-7325 1375) $PN BV5
J 2
(-7335 1385);
DISPLAY 0.617021 (-7335 1385);
PAINT ORANGE (-7335 1385);
FORCEPROP 2 LASTPIN (-7325 1325) $PN BU10
J 2
(-7335 1335);
DISPLAY 0.617021 (-7335 1335);
PAINT ORANGE (-7335 1335);
FORCEPROP 2 LASTPIN (-7325 1275) $PN BV17
J 2
(-7335 1285);
DISPLAY 0.617021 (-7335 1285);
PAINT ORANGE (-7335 1285);
FORCEPROP 2 LASTPIN (-7325 1225) $PN BV25
J 2
(-7335 1235);
DISPLAY 0.617021 (-7335 1235);
PAINT ORANGE (-7335 1235);
FORCEPROP 2 LASTPIN (-7325 1175) $PN BW6
J 2
(-7335 1185);
DISPLAY 0.617021 (-7335 1185);
PAINT ORANGE (-7335 1185);
FORCEPROP 2 LASTPIN (-7325 1125) $PN P55
J 2
(-7335 1135);
DISPLAY 0.617021 (-7335 1135);
PAINT ORANGE (-7335 1135);
FORCEPROP 2 LASTPIN (-7325 1075) $PN BW12
J 2
(-7335 1085);
DISPLAY 0.617021 (-7335 1085);
PAINT ORANGE (-7335 1085);
FORCEPROP 2 LASTPIN (-7325 1025) $PN BW14
J 2
(-7335 1035);
DISPLAY 0.617021 (-7335 1035);
PAINT ORANGE (-7335 1035);
FORCEPROP 2 LASTPIN (-7325 975) $PN BW16
J 2
(-7335 985);
DISPLAY 0.617021 (-7335 985);
PAINT ORANGE (-7335 985);
FORCEPROP 2 LASTPIN (-7325 925) $PN BW18
J 2
(-7335 935);
DISPLAY 0.617021 (-7335 935);
PAINT ORANGE (-7335 935);
FORCEPROP 2 LASTPIN (-7325 875) $PN BW26
J 2
(-7335 885);
DISPLAY 0.617021 (-7335 885);
PAINT ORANGE (-7335 885);
FORCEPROP 2 LASTPIN (-7325 825) $PN BW72
J 2
(-7335 835);
DISPLAY 0.617021 (-7335 835);
PAINT ORANGE (-7335 835);
FORCEPROP 2 LASTPIN (-7325 775) $PN BW74
J 2
(-7335 785);
DISPLAY 0.617021 (-7335 785);
PAINT ORANGE (-7335 785);
FORCEPROP 2 LASTPIN (-7325 725) $PN BW76
J 2
(-7335 735);
DISPLAY 0.617021 (-7335 735);
PAINT ORANGE (-7335 735);
FORCEPROP 2 LASTPIN (-7325 675) $PN BW78
J 2
(-7335 685);
DISPLAY 0.617021 (-7335 685);
PAINT ORANGE (-7335 685);
FORCEPROP 2 LASTPIN (-7325 625) $PN BW80
J 2
(-7335 635);
DISPLAY 0.617021 (-7335 635);
PAINT ORANGE (-7335 635);
FORCEPROP 2 LASTPIN (-7325 575) $PN BW82
J 2
(-7335 585);
DISPLAY 0.617021 (-7335 585);
PAINT ORANGE (-7335 585);
FORCEPROP 2 LASTPIN (-6125 4525) $PN BY11
J 0
(-6115 4535);
DISPLAY 0.617021 (-6115 4535);
PAINT ORANGE (-6115 4535);
FORCEPROP 2 LASTPIN (-6125 4475) $PN BY13
J 0
(-6115 4485);
DISPLAY 0.617021 (-6115 4485);
PAINT ORANGE (-6115 4485);
FORCEPROP 2 LASTPIN (-6125 4425) $PN BY23
J 0
(-6115 4435);
DISPLAY 0.617021 (-6115 4435);
PAINT ORANGE (-6115 4435);
FORCEPROP 2 LASTPIN (-6125 4375) $PN BY63
J 0
(-6115 4385);
DISPLAY 0.617021 (-6115 4385);
PAINT ORANGE (-6115 4385);
FORCEPROP 2 LASTPIN (-6125 4325) $PN BY65
J 0
(-6115 4335);
DISPLAY 0.617021 (-6115 4335);
PAINT ORANGE (-6115 4335);
FORCEPROP 2 LASTPIN (-6125 4275) $PN BY67
J 0
(-6115 4285);
DISPLAY 0.617021 (-6115 4285);
PAINT ORANGE (-6115 4285);
FORCEPROP 2 LASTPIN (-6125 4225) $PN BY69
J 0
(-6115 4235);
DISPLAY 0.617021 (-6115 4235);
PAINT ORANGE (-6115 4235);
FORCEPROP 2 LASTPIN (-6125 4175) $PN BY71
J 0
(-6115 4185);
DISPLAY 0.617021 (-6115 4185);
PAINT ORANGE (-6115 4185);
FORCEPROP 2 LASTPIN (-6125 4125) $PN CA2
J 0
(-6115 4135);
DISPLAY 0.617021 (-6115 4135);
PAINT ORANGE (-6115 4135);
FORCEPROP 2 LASTPIN (-6125 4075) $PN CA6
J 0
(-6115 4085);
DISPLAY 0.617021 (-6115 4085);
PAINT ORANGE (-6115 4085);
FORCEPROP 2 LASTPIN (-6125 4025) $PN CA8
J 0
(-6115 4035);
DISPLAY 0.617021 (-6115 4035);
PAINT ORANGE (-6115 4035);
FORCEPROP 2 LASTPIN (-6125 3975) $PN CA10
J 0
(-6115 3985);
DISPLAY 0.617021 (-6115 3985);
PAINT ORANGE (-6115 3985);
FORCEPROP 2 LASTPIN (-6125 3925) $PN CA14
J 0
(-6115 3935);
DISPLAY 0.617021 (-6115 3935);
PAINT ORANGE (-6115 3935);
FORCEPROP 2 LASTPIN (-6125 3875) $PN CA18
J 0
(-6115 3885);
DISPLAY 0.617021 (-6115 3885);
PAINT ORANGE (-6115 3885);
FORCEPROP 2 LASTPIN (-6125 3825) $PN CA26
J 0
(-6115 3835);
DISPLAY 0.617021 (-6115 3835);
PAINT ORANGE (-6115 3835);
FORCEPROP 2 LASTPIN (-6125 3775) $PN CA64
J 0
(-6115 3785);
DISPLAY 0.617021 (-6115 3785);
PAINT ORANGE (-6115 3785);
FORCEPROP 2 LASTPIN (-6125 3725) $PN CA66
J 0
(-6115 3735);
DISPLAY 0.617021 (-6115 3735);
PAINT ORANGE (-6115 3735);
FORCEPROP 2 LASTPIN (-6125 3675) $PN CA68
J 0
(-6115 3685);
DISPLAY 0.617021 (-6115 3685);
PAINT ORANGE (-6115 3685);
FORCEPROP 2 LASTPIN (-6125 3625) $PN CA70
J 0
(-6115 3635);
DISPLAY 0.617021 (-6115 3635);
PAINT ORANGE (-6115 3635);
FORCEPROP 2 LASTPIN (-6125 3575) $PN CB7
J 0
(-6115 3585);
DISPLAY 0.617021 (-6115 3585);
PAINT ORANGE (-6115 3585);
FORCEPROP 2 LASTPIN (-6125 3525) $PN CB9
J 0
(-6115 3535);
DISPLAY 0.617021 (-6115 3535);
PAINT ORANGE (-6115 3535);
FORCEPROP 2 LASTPIN (-6125 3475) $PN CB27
J 0
(-6115 3485);
DISPLAY 0.617021 (-6115 3485);
PAINT ORANGE (-6115 3485);
FORCEPROP 2 LASTPIN (-6125 3425) $PN CB63
J 0
(-6115 3435);
DISPLAY 0.617021 (-6115 3435);
PAINT ORANGE (-6115 3435);
FORCEPROP 2 LASTPIN (-6125 3375) $PN CB71
J 0
(-6115 3385);
DISPLAY 0.617021 (-6115 3385);
PAINT ORANGE (-6115 3385);
FORCEPROP 2 LASTPIN (-6125 3325) $PN CC4
J 0
(-6115 3335);
DISPLAY 0.617021 (-6115 3335);
PAINT ORANGE (-6115 3335);
FORCEPROP 2 LASTPIN (-6125 3275) $PN CC16
J 0
(-6115 3285);
DISPLAY 0.617021 (-6115 3285);
PAINT ORANGE (-6115 3285);
FORCEPROP 2 LASTPIN (-6125 3225) $PN CC18
J 0
(-6115 3235);
DISPLAY 0.617021 (-6115 3235);
PAINT ORANGE (-6115 3235);
FORCEPROP 2 LASTPIN (-6125 3175) $PN CC24
J 0
(-6115 3185);
DISPLAY 0.617021 (-6115 3185);
PAINT ORANGE (-6115 3185);
FORCEPROP 2 LASTPIN (-6125 3125) $PN CC64
J 0
(-6115 3135);
DISPLAY 0.617021 (-6115 3135);
PAINT ORANGE (-6115 3135);
FORCEPROP 2 LASTPIN (-6125 3075) $PN CC72
J 0
(-6115 3085);
DISPLAY 0.617021 (-6115 3085);
PAINT ORANGE (-6115 3085);
FORCEPROP 2 LASTPIN (-6125 3025) $PN CC74
J 0
(-6115 3035);
DISPLAY 0.617021 (-6115 3035);
PAINT ORANGE (-6115 3035);
FORCEPROP 2 LASTPIN (-6125 2975) $PN CC76
J 0
(-6115 2985);
DISPLAY 0.617021 (-6115 2985);
PAINT ORANGE (-6115 2985);
FORCEPROP 2 LASTPIN (-6125 2925) $PN CC78
J 0
(-6115 2935);
DISPLAY 0.617021 (-6115 2935);
PAINT ORANGE (-6115 2935);
FORCEPROP 2 LASTPIN (-6125 2875) $PN CC80
J 0
(-6115 2885);
DISPLAY 0.617021 (-6115 2885);
PAINT ORANGE (-6115 2885);
FORCEPROP 2 LASTPIN (-6125 2825) $PN CC82
J 0
(-6115 2835);
DISPLAY 0.617021 (-6115 2835);
PAINT ORANGE (-6115 2835);
FORCEPROP 2 LASTPIN (-6125 2775) $PN CD5
J 0
(-6115 2785);
DISPLAY 0.617021 (-6115 2785);
PAINT ORANGE (-6115 2785);
FORCEPROP 2 LASTPIN (-6125 2675) $PN CD63
J 0
(-6115 2685);
DISPLAY 0.617021 (-6115 2685);
PAINT ORANGE (-6115 2685);
FORCEPROP 2 LASTPIN (-6125 2625) $PN CD73
J 0
(-6115 2635);
DISPLAY 0.617021 (-6115 2635);
PAINT ORANGE (-6115 2635);
FORCEPROP 2 LASTPIN (-6125 2575) $PN CD75
J 0
(-6115 2585);
DISPLAY 0.617021 (-6115 2585);
PAINT ORANGE (-6115 2585);
FORCEPROP 2 LASTPIN (-6125 2525) $PN CD77
J 0
(-6115 2535);
DISPLAY 0.617021 (-6115 2535);
PAINT ORANGE (-6115 2535);
FORCEPROP 2 LASTPIN (-6125 2475) $PN CD79
J 0
(-6115 2485);
DISPLAY 0.617021 (-6115 2485);
PAINT ORANGE (-6115 2485);
FORCEPROP 2 LASTPIN (-6125 2425) $PN CD81
J 0
(-6115 2435);
DISPLAY 0.617021 (-6115 2435);
PAINT ORANGE (-6115 2435);
FORCEPROP 2 LASTPIN (-6125 2375) $PN CE10
J 0
(-6115 2385);
DISPLAY 0.617021 (-6115 2385);
PAINT ORANGE (-6115 2385);
FORCEPROP 2 LASTPIN (-6125 2325) $PN CE14
J 0
(-6115 2335);
DISPLAY 0.617021 (-6115 2335);
PAINT ORANGE (-6115 2335);
FORCEPROP 2 LASTPIN (-6125 2275) $PN CE20
J 0
(-6115 2285);
DISPLAY 0.617021 (-6115 2285);
PAINT ORANGE (-6115 2285);
FORCEPROP 2 LASTPIN (-6125 2225) $PN CE26
J 0
(-6115 2235);
DISPLAY 0.617021 (-6115 2235);
PAINT ORANGE (-6115 2235);
FORCEPROP 2 LASTPIN (-6125 2175) $PN CE62
J 0
(-6115 2185);
DISPLAY 0.617021 (-6115 2185);
PAINT ORANGE (-6115 2185);
FORCEPROP 2 LASTPIN (-6125 2125) $PN CE70
J 0
(-6115 2135);
DISPLAY 0.617021 (-6115 2135);
PAINT ORANGE (-6115 2135);
FORCEPROP 2 LASTPIN (-6125 2075) $PN CE82
J 0
(-6115 2085);
DISPLAY 0.617021 (-6115 2085);
PAINT ORANGE (-6115 2085);
FORCEPROP 2 LASTPIN (-6125 2025) $PN P53
J 0
(-6115 2035);
DISPLAY 0.617021 (-6115 2035);
PAINT ORANGE (-6115 2035);
FORCEPROP 2 LASTPIN (-6125 1975) $PN CF9
J 0
(-6115 1985);
DISPLAY 0.617021 (-6115 1985);
PAINT ORANGE (-6115 1985);
FORCEPROP 2 LASTPIN (-6125 1925) $PN CF63
J 0
(-6115 1935);
DISPLAY 0.617021 (-6115 1935);
PAINT ORANGE (-6115 1935);
FORCEPROP 2 LASTPIN (-6125 1875) $PN CF69
J 0
(-6115 1885);
DISPLAY 0.617021 (-6115 1885);
PAINT ORANGE (-6115 1885);
FORCEPROP 2 LASTPIN (-6125 1825) $PN CF71
J 0
(-6115 1835);
DISPLAY 0.617021 (-6115 1835);
PAINT ORANGE (-6115 1835);
FORCEPROP 2 LASTPIN (-6125 1775) $PN CF77
J 0
(-6115 1785);
DISPLAY 0.617021 (-6115 1785);
PAINT ORANGE (-6115 1785);
FORCEPROP 2 LASTPIN (-6125 1725) $PN CF83
J 0
(-6115 1735);
DISPLAY 0.617021 (-6115 1735);
PAINT ORANGE (-6115 1735);
FORCEPROP 2 LASTPIN (-6125 1675) $PN P51
J 0
(-6115 1685);
DISPLAY 0.617021 (-6115 1685);
PAINT ORANGE (-6115 1685);
FORCEPROP 2 LASTPIN (-6125 1625) $PN CG18
J 0
(-6115 1635);
DISPLAY 0.617021 (-6115 1635);
PAINT ORANGE (-6115 1635);
FORCEPROP 2 LASTPIN (-6125 1575) $PN CG22
J 0
(-6115 1585);
DISPLAY 0.617021 (-6115 1585);
PAINT ORANGE (-6115 1585);
FORCEPROP 2 LASTPIN (-6125 1525) $PN CG62
J 0
(-6115 1535);
DISPLAY 0.617021 (-6115 1535);
PAINT ORANGE (-6115 1535);
FORCEPROP 2 LASTPIN (-6125 1475) $PN CG68
J 0
(-6115 1485);
DISPLAY 0.617021 (-6115 1485);
PAINT ORANGE (-6115 1485);
FORCEPROP 2 LASTPIN (-6125 1425) $PN CG72
J 0
(-6115 1435);
DISPLAY 0.617021 (-6115 1435);
PAINT ORANGE (-6115 1435);
FORCEPROP 2 LASTPIN (-6125 1375) $PN CG80
J 0
(-6115 1385);
DISPLAY 0.617021 (-6115 1385);
PAINT ORANGE (-6115 1385);
FORCEPROP 2 LASTPIN (-6125 1325) $PN CH1
J 0
(-6115 1335);
DISPLAY 0.617021 (-6115 1335);
PAINT ORANGE (-6115 1335);
FORCEPROP 2 LASTPIN (-6125 1275) $PN CH3
J 0
(-6115 1285);
DISPLAY 0.617021 (-6115 1285);
PAINT ORANGE (-6115 1285);
FORCEPROP 2 LASTPIN (-6125 1225) $PN CH15
J 0
(-6115 1235);
DISPLAY 0.617021 (-6115 1235);
PAINT ORANGE (-6115 1235);
FORCEPROP 2 LASTPIN (-6125 1175) $PN CH19
J 0
(-6115 1185);
DISPLAY 0.617021 (-6115 1185);
PAINT ORANGE (-6115 1185);
FORCEPROP 2 LASTPIN (-6125 1125) $PN CH63
J 0
(-6115 1135);
DISPLAY 0.617021 (-6115 1135);
PAINT ORANGE (-6115 1135);
FORCEPROP 2 LASTPIN (-6125 1075) $PN CH67
J 0
(-6115 1085);
DISPLAY 0.617021 (-6115 1085);
PAINT ORANGE (-6115 1085);
FORCEPROP 2 LASTPIN (-6125 1025) $PN CH73
J 0
(-6115 1035);
DISPLAY 0.617021 (-6115 1035);
PAINT ORANGE (-6115 1035);
FORCEPROP 2 LASTPIN (-6125 975) $PN CH79
J 0
(-6115 985);
DISPLAY 0.617021 (-6115 985);
PAINT ORANGE (-6115 985);
FORCEPROP 2 LASTPIN (-6125 925) $PN CH81
J 0
(-6115 935);
DISPLAY 0.617021 (-6115 935);
PAINT ORANGE (-6115 935);
FORCEPROP 2 LASTPIN (-6125 875) $PN CH83
J 0
(-6115 885);
DISPLAY 0.617021 (-6115 885);
PAINT ORANGE (-6115 885);
FORCEPROP 2 LASTPIN (-6125 825) $PN CJ2
J 0
(-6115 835);
DISPLAY 0.617021 (-6115 835);
PAINT ORANGE (-6115 835);
FORCEPROP 2 LASTPIN (-6125 775) $PN CJ6
J 0
(-6115 785);
DISPLAY 0.617021 (-6115 785);
PAINT ORANGE (-6115 785);
FORCEPROP 2 LASTPIN (-6125 725) $PN CJ8
J 0
(-6115 735);
DISPLAY 0.617021 (-6115 735);
PAINT ORANGE (-6115 735);
FORCEPROP 2 LASTPIN (-6125 675) $PN CJ10
J 0
(-6115 685);
DISPLAY 0.617021 (-6115 685);
PAINT ORANGE (-6115 685);
FORCEPROP 2 LASTPIN (-6125 625) $PN CJ12
J 0
(-6115 635);
DISPLAY 0.617021 (-6115 635);
PAINT ORANGE (-6115 635);
FORCEPROP 2 LASTPIN (-6125 575) $PN P49
J 0
(-6115 585);
DISPLAY 0.617021 (-6115 585);
PAINT ORANGE (-6115 585);
FORCEPROP 2 LASTPIN (-6125 2725) $PN CD13
J 0
(-6115 2735);
DISPLAY 0.617021 (-6115 2735);
PAINT ORANGE (-6115 2735);
FORCEPROP 2 LASTPIN (-7325 4525) $PN BG74
J 2
(-7335 4535);
DISPLAY 0.617021 (-7335 4535);
PAINT ORANGE (-7335 4535);
FORCEPROP 1 LAST PACK_TYPE BGA1
J 0
(-7275 4825);
PAINT SKYBLUE (-7275 4825);
DISPLAY INVISIBLE (-7275 4825);
FORCEPROP 2 LAST SEC_TYPE BGA1
J 0
(-7275 4825);
DISPLAY 1.021277 (-7275 4825);
PAINT ORANGE (-7275 4825);
DISPLAY INVISIBLE (-7275 4825);
FORCEPROP 2 LAST CDS_LIB chpset_lib
J 0
(-6725 2525);
PAINT ORANGE (-6725 2525);
DISPLAY INVISIBLE (-6725 2525);
FORCEPROP 2 LAST SEC 27
J 0
(-7275 4825);
DISPLAY 0.680851 (-7275 4825);
PAINT MONO (-7275 4825);
DISPLAY INVISIBLE (-7275 4825);
FORCEPROP 2 LAST CDS_LOCATION U2D1
J 0
(-7275 4775);
DISPLAY 0.617021 (-7275 4775);
PAINT AQUA (-7275 4775);
DISPLAY INVISIBLE (-7275 4775);
FORCEPROP 1 LAST PATH I17
J 0
(-6725 4725);
PAINT GREEN (-6725 4725);
DISPLAY INVISIBLE (-6725 4725);
FORCEADD SKX_EXT_B..28
(-4925 2525);
FORCEPROP 1 LAST LOCATION U2D1
J 0
(-5475 4775);
DISPLAY 0.617021 (-5475 4775);
PAINT AQUA (-5475 4775);
FORCEPROP 1 LAST PART_NUMBER TBD
J 0
(-5475 375);
DISPLAY 0.617021 (-5475 375);
PAINT BLUE (-5475 375);
FORCEPROP 1 LAST MATERIAL IC
J 0
(-5475 4725);
DISPLAY 0.617021 (-5475 4725);
PAINT SKYBLUE (-5475 4725);
FORCEPROP 2 LASTPIN (-5525 4525) $PN P47
J 2
(-5535 4535);
DISPLAY 0.617021 (-5535 4535);
PAINT ORANGE (-5535 4535);
FORCEPROP 2 LASTPIN (-5525 4475) $PN CJ62
J 2
(-5535 4485);
DISPLAY 0.617021 (-5535 4485);
PAINT ORANGE (-5535 4485);
FORCEPROP 2 LASTPIN (-5525 4425) $PN CJ74
J 2
(-5535 4435);
DISPLAY 0.617021 (-5535 4435);
PAINT ORANGE (-5535 4435);
FORCEPROP 2 LASTPIN (-5525 4375) $PN CJ76
J 2
(-5535 4385);
DISPLAY 0.617021 (-5535 4385);
PAINT ORANGE (-5535 4385);
FORCEPROP 2 LASTPIN (-5525 4325) $PN CJ78
J 2
(-5535 4335);
DISPLAY 0.617021 (-5535 4335);
PAINT ORANGE (-5535 4335);
FORCEPROP 2 LASTPIN (-5525 4275) $PN CJ82
J 2
(-5535 4285);
DISPLAY 0.617021 (-5535 4285);
PAINT ORANGE (-5535 4285);
FORCEPROP 2 LASTPIN (-5525 4225) $PN CJ84
J 2
(-5535 4235);
DISPLAY 0.617021 (-5535 4235);
PAINT ORANGE (-5535 4235);
FORCEPROP 2 LASTPIN (-5525 4175) $PN CJ86
J 2
(-5535 4185);
DISPLAY 0.617021 (-5535 4185);
PAINT ORANGE (-5535 4185);
FORCEPROP 2 LASTPIN (-5525 4125) $PN CK11
J 2
(-5535 4135);
DISPLAY 0.617021 (-5535 4135);
PAINT ORANGE (-5535 4135);
FORCEPROP 2 LASTPIN (-5525 4075) $PN CK15
J 2
(-5535 4085);
DISPLAY 0.617021 (-5535 4085);
PAINT ORANGE (-5535 4085);
FORCEPROP 2 LASTPIN (-5525 4025) $PN CK21
J 2
(-5535 4035);
DISPLAY 0.617021 (-5535 4035);
PAINT ORANGE (-5535 4035);
FORCEPROP 2 LASTPIN (-5525 3975) $PN CK27
J 2
(-5535 3985);
DISPLAY 0.617021 (-5535 3985);
PAINT ORANGE (-5535 3985);
FORCEPROP 2 LASTPIN (-5525 3925) $PN CK63
J 2
(-5535 3935);
DISPLAY 0.617021 (-5535 3935);
PAINT ORANGE (-5535 3935);
FORCEPROP 2 LASTPIN (-5525 3875) $PN CK65
J 2
(-5535 3885);
DISPLAY 0.617021 (-5535 3885);
PAINT ORANGE (-5535 3885);
FORCEPROP 2 LASTPIN (-5525 3825) $PN CK67
J 2
(-5535 3835);
DISPLAY 0.617021 (-5535 3835);
PAINT ORANGE (-5535 3835);
FORCEPROP 2 LASTPIN (-5525 3775) $PN CK69
J 2
(-5535 3785);
DISPLAY 0.617021 (-5535 3785);
PAINT ORANGE (-5535 3785);
FORCEPROP 2 LASTPIN (-5525 3725) $PN CK71
J 2
(-5535 3735);
DISPLAY 0.617021 (-5535 3735);
PAINT ORANGE (-5535 3735);
FORCEPROP 2 LASTPIN (-5525 3675) $PN CK73
J 2
(-5535 3685);
DISPLAY 0.617021 (-5535 3685);
PAINT ORANGE (-5535 3685);
FORCEPROP 2 LASTPIN (-5525 3625) $PN CK75
J 2
(-5535 3635);
DISPLAY 0.617021 (-5535 3635);
PAINT ORANGE (-5535 3635);
FORCEPROP 2 LASTPIN (-5525 3575) $PN CK83
J 2
(-5535 3585);
DISPLAY 0.617021 (-5535 3585);
PAINT ORANGE (-5535 3585);
FORCEPROP 2 LASTPIN (-5525 3525) $PN CK85
J 2
(-5535 3535);
DISPLAY 0.617021 (-5535 3535);
PAINT ORANGE (-5535 3535);
FORCEPROP 2 LASTPIN (-5525 3475) $PN CL8
J 2
(-5535 3485);
DISPLAY 0.617021 (-5535 3485);
PAINT ORANGE (-5535 3485);
FORCEPROP 2 LASTPIN (-5525 3425) $PN CL14
J 2
(-5535 3435);
DISPLAY 0.617021 (-5535 3435);
PAINT ORANGE (-5535 3435);
FORCEPROP 2 LASTPIN (-5525 3375) $PN CL18
J 2
(-5535 3385);
DISPLAY 0.617021 (-5535 3385);
PAINT ORANGE (-5535 3385);
FORCEPROP 2 LASTPIN (-5525 3325) $PN P45
J 2
(-5535 3335);
DISPLAY 0.617021 (-5535 3335);
PAINT ORANGE (-5535 3335);
FORCEPROP 2 LASTPIN (-5525 3275) $PN H63
J 2
(-5535 3285);
DISPLAY 0.617021 (-5535 3285);
PAINT ORANGE (-5535 3285);
FORCEPROP 2 LASTPIN (-5525 3225) $PN CL62
J 2
(-5535 3235);
DISPLAY 0.617021 (-5535 3235);
PAINT ORANGE (-5535 3235);
FORCEPROP 2 LASTPIN (-5525 3175) $PN CL64
J 2
(-5535 3185);
DISPLAY 0.617021 (-5535 3185);
PAINT ORANGE (-5535 3185);
FORCEPROP 2 LASTPIN (-5525 3125) $PN CL66
J 2
(-5535 3135);
DISPLAY 0.617021 (-5535 3135);
PAINT ORANGE (-5535 3135);
FORCEPROP 2 LASTPIN (-5525 3075) $PN CL74
J 2
(-5535 3085);
DISPLAY 0.617021 (-5535 3085);
PAINT ORANGE (-5535 3085);
FORCEPROP 2 LASTPIN (-5525 3025) $PN CL76
J 2
(-5535 3035);
DISPLAY 0.617021 (-5535 3035);
PAINT ORANGE (-5535 3035);
FORCEPROP 2 LASTPIN (-5525 2975) $PN CL78
J 2
(-5535 2985);
DISPLAY 0.617021 (-5535 2985);
PAINT ORANGE (-5535 2985);
FORCEPROP 2 LASTPIN (-5525 2925) $PN CL80
J 2
(-5535 2935);
DISPLAY 0.617021 (-5535 2935);
PAINT ORANGE (-5535 2935);
FORCEPROP 2 LASTPIN (-5525 2875) $PN CM19
J 2
(-5535 2885);
DISPLAY 0.617021 (-5535 2885);
PAINT ORANGE (-5535 2885);
FORCEPROP 2 LASTPIN (-5525 2825) $PN CM29
J 2
(-5535 2835);
DISPLAY 0.617021 (-5535 2835);
PAINT ORANGE (-5535 2835);
FORCEPROP 2 LASTPIN (-5525 2775) $PN CM5
J 2
(-5535 2785);
DISPLAY 0.617021 (-5535 2785);
PAINT ORANGE (-5535 2785);
FORCEPROP 2 LASTPIN (-5525 2725) $PN CM31
J 2
(-5535 2735);
DISPLAY 0.617021 (-5535 2735);
PAINT ORANGE (-5535 2735);
FORCEPROP 2 LASTPIN (-5525 2675) $PN CM61
J 2
(-5535 2685);
DISPLAY 0.617021 (-5535 2685);
PAINT ORANGE (-5535 2685);
FORCEPROP 2 LASTPIN (-5525 2625) $PN CM63
J 2
(-5535 2635);
DISPLAY 0.617021 (-5535 2635);
PAINT ORANGE (-5535 2635);
FORCEPROP 2 LASTPIN (-5525 2575) $PN CM67
J 2
(-5535 2585);
DISPLAY 0.617021 (-5535 2585);
PAINT ORANGE (-5535 2585);
FORCEPROP 2 LASTPIN (-5525 2525) $PN CM73
J 2
(-5535 2535);
DISPLAY 0.617021 (-5535 2535);
PAINT ORANGE (-5535 2535);
FORCEPROP 2 LASTPIN (-5525 2475) $PN CM77
J 2
(-5535 2485);
DISPLAY 0.617021 (-5535 2485);
PAINT ORANGE (-5535 2485);
FORCEPROP 2 LASTPIN (-5525 2425) $PN CM83
J 2
(-5535 2435);
DISPLAY 0.617021 (-5535 2435);
PAINT ORANGE (-5535 2435);
FORCEPROP 2 LASTPIN (-5525 2375) $PN CM85
J 2
(-5535 2385);
DISPLAY 0.617021 (-5535 2385);
PAINT ORANGE (-5535 2385);
FORCEPROP 2 LASTPIN (-5525 2325) $PN CN2
J 2
(-5535 2335);
DISPLAY 0.617021 (-5535 2335);
PAINT ORANGE (-5535 2335);
FORCEPROP 2 LASTPIN (-5525 2275) $PN CN12
J 2
(-5535 2285);
DISPLAY 0.617021 (-5535 2285);
PAINT ORANGE (-5535 2285);
FORCEPROP 2 LASTPIN (-5525 2225) $PN H61
J 2
(-5535 2235);
DISPLAY 0.617021 (-5535 2235);
PAINT ORANGE (-5535 2235);
FORCEPROP 2 LASTPIN (-5525 2175) $PN CN26
J 2
(-5535 2185);
DISPLAY 0.617021 (-5535 2185);
PAINT ORANGE (-5535 2185);
FORCEPROP 2 LASTPIN (-5525 2125) $PN CN32
J 2
(-5535 2135);
DISPLAY 0.617021 (-5535 2135);
PAINT ORANGE (-5535 2135);
FORCEPROP 2 LASTPIN (-5525 2075) $PN CN60
J 2
(-5535 2085);
DISPLAY 0.617021 (-5535 2085);
PAINT ORANGE (-5535 2085);
FORCEPROP 2 LASTPIN (-5525 2025) $PN CN62
J 2
(-5535 2035);
DISPLAY 0.617021 (-5535 2035);
PAINT ORANGE (-5535 2035);
FORCEPROP 2 LASTPIN (-5525 1975) $PN CN68
J 2
(-5535 1985);
DISPLAY 0.617021 (-5535 1985);
PAINT ORANGE (-5535 1985);
FORCEPROP 2 LASTPIN (-5525 1925) $PN CN78
J 2
(-5535 1935);
DISPLAY 0.617021 (-5535 1935);
PAINT ORANGE (-5535 1935);
FORCEPROP 2 LASTPIN (-5525 1875) $PN CP1
J 2
(-5535 1885);
DISPLAY 0.617021 (-5535 1885);
PAINT ORANGE (-5535 1885);
FORCEPROP 2 LASTPIN (-5525 1825) $PN H59
J 2
(-5535 1835);
DISPLAY 0.617021 (-5535 1835);
PAINT ORANGE (-5535 1835);
FORCEPROP 2 LASTPIN (-5525 1775) $PN CP25
J 2
(-5535 1785);
DISPLAY 0.617021 (-5535 1785);
PAINT ORANGE (-5535 1785);
FORCEPROP 2 LASTPIN (-5525 1725) $PN CP59
J 2
(-5535 1735);
DISPLAY 0.617021 (-5535 1735);
PAINT ORANGE (-5535 1735);
FORCEPROP 2 LASTPIN (-5525 1675) $PN CP69
J 2
(-5535 1685);
DISPLAY 0.617021 (-5535 1685);
PAINT ORANGE (-5535 1685);
FORCEPROP 2 LASTPIN (-5525 1625) $PN CP73
J 2
(-5535 1635);
DISPLAY 0.617021 (-5535 1635);
PAINT ORANGE (-5535 1635);
FORCEPROP 2 LASTPIN (-5525 1575) $PN CP75
J 2
(-5535 1585);
DISPLAY 0.617021 (-5535 1585);
PAINT ORANGE (-5535 1585);
FORCEPROP 2 LASTPIN (-5525 1525) $PN CP81
J 2
(-5535 1535);
DISPLAY 0.617021 (-5535 1535);
PAINT ORANGE (-5535 1535);
FORCEPROP 2 LASTPIN (-5525 1475) $PN CP83
J 2
(-5535 1485);
DISPLAY 0.617021 (-5535 1485);
PAINT ORANGE (-5535 1485);
FORCEPROP 2 LASTPIN (-5525 1425) $PN CR6
J 2
(-5535 1435);
DISPLAY 0.617021 (-5535 1435);
PAINT ORANGE (-5535 1435);
FORCEPROP 2 LASTPIN (-5525 1375) $PN CR10
J 2
(-5535 1385);
DISPLAY 0.617021 (-5535 1385);
PAINT ORANGE (-5535 1385);
FORCEPROP 2 LASTPIN (-5525 1325) $PN CR22
J 2
(-5535 1335);
DISPLAY 0.617021 (-5535 1335);
PAINT ORANGE (-5535 1335);
FORCEPROP 2 LASTPIN (-5525 1275) $PN CR24
J 2
(-5535 1285);
DISPLAY 0.617021 (-5535 1285);
PAINT ORANGE (-5535 1285);
FORCEPROP 2 LASTPIN (-5525 1225) $PN CR32
J 2
(-5535 1235);
DISPLAY 0.617021 (-5535 1235);
PAINT ORANGE (-5535 1235);
FORCEPROP 2 LASTPIN (-5525 1175) $PN CR58
J 2
(-5535 1185);
DISPLAY 0.617021 (-5535 1185);
PAINT ORANGE (-5535 1185);
FORCEPROP 2 LASTPIN (-5525 1125) $PN CR62
J 2
(-5535 1135);
DISPLAY 0.617021 (-5535 1135);
PAINT ORANGE (-5535 1135);
FORCEPROP 2 LASTPIN (-5525 1075) $PN CR64
J 2
(-5535 1085);
DISPLAY 0.617021 (-5535 1085);
PAINT ORANGE (-5535 1085);
FORCEPROP 2 LASTPIN (-5525 1025) $PN CR66
J 2
(-5535 1035);
DISPLAY 0.617021 (-5535 1035);
PAINT ORANGE (-5535 1035);
FORCEPROP 2 LASTPIN (-5525 975) $PN CR68
J 2
(-5535 985);
DISPLAY 0.617021 (-5535 985);
PAINT ORANGE (-5535 985);
FORCEPROP 2 LASTPIN (-5525 925) $PN CR78
J 2
(-5535 935);
DISPLAY 0.617021 (-5535 935);
PAINT ORANGE (-5535 935);
FORCEPROP 2 LASTPIN (-5525 875) $PN CR86
J 2
(-5535 885);
DISPLAY 0.617021 (-5535 885);
PAINT ORANGE (-5535 885);
FORCEPROP 2 LASTPIN (-5525 825) $PN H57
J 2
(-5535 835);
DISPLAY 0.617021 (-5535 835);
PAINT ORANGE (-5535 835);
FORCEPROP 2 LASTPIN (-5525 775) $PN CT13
J 2
(-5535 785);
DISPLAY 0.617021 (-5535 785);
PAINT ORANGE (-5535 785);
FORCEPROP 2 LASTPIN (-5525 725) $PN CT19
J 2
(-5535 735);
DISPLAY 0.617021 (-5535 735);
PAINT ORANGE (-5535 735);
FORCEPROP 2 LASTPIN (-5525 675) $PN CT27
J 2
(-5535 685);
DISPLAY 0.617021 (-5535 685);
PAINT ORANGE (-5535 685);
FORCEPROP 2 LASTPIN (-5525 625) $PN CT29
J 2
(-5535 635);
DISPLAY 0.617021 (-5535 635);
PAINT ORANGE (-5535 635);
FORCEPROP 2 LASTPIN (-5525 575) $PN CT33
J 2
(-5535 585);
DISPLAY 0.617021 (-5535 585);
PAINT ORANGE (-5535 585);
FORCEPROP 2 LASTPIN (-4325 4525) $PN CT35
J 0
(-4315 4535);
DISPLAY 0.617021 (-4315 4535);
PAINT ORANGE (-4315 4535);
FORCEPROP 2 LASTPIN (-4325 4475) $PN CT57
J 0
(-4315 4485);
DISPLAY 0.617021 (-4315 4485);
PAINT ORANGE (-4315 4485);
FORCEPROP 2 LASTPIN (-4325 4425) $PN CT73
J 0
(-4315 4435);
DISPLAY 0.617021 (-4315 4435);
PAINT ORANGE (-4315 4435);
FORCEPROP 2 LASTPIN (-4325 4375) $PN CT79
J 0
(-4315 4385);
DISPLAY 0.617021 (-4315 4385);
PAINT ORANGE (-4315 4385);
FORCEPROP 2 LASTPIN (-4325 4325) $PN CT83
J 0
(-4315 4335);
DISPLAY 0.617021 (-4315 4335);
PAINT ORANGE (-4315 4335);
FORCEPROP 2 LASTPIN (-4325 4275) $PN CT85
J 0
(-4315 4285);
DISPLAY 0.617021 (-4315 4285);
PAINT ORANGE (-4315 4285);
FORCEPROP 2 LASTPIN (-4325 4225) $PN CU4
J 0
(-4315 4235);
DISPLAY 0.617021 (-4315 4235);
PAINT ORANGE (-4315 4235);
FORCEPROP 2 LASTPIN (-4325 4175) $PN CU22
J 0
(-4315 4185);
DISPLAY 0.617021 (-4315 4185);
PAINT ORANGE (-4315 4185);
FORCEPROP 2 LASTPIN (-4325 4125) $PN CU28
J 0
(-4315 4135);
DISPLAY 0.617021 (-4315 4135);
PAINT ORANGE (-4315 4135);
FORCEPROP 2 LASTPIN (-4325 4075) $PN CU30
J 0
(-4315 4085);
DISPLAY 0.617021 (-4315 4085);
PAINT ORANGE (-4315 4085);
FORCEPROP 2 LASTPIN (-4325 4025) $PN CU34
J 0
(-4315 4035);
DISPLAY 0.617021 (-4315 4035);
PAINT ORANGE (-4315 4035);
FORCEPROP 2 LASTPIN (-4325 3975) $PN CU36
J 0
(-4315 3985);
DISPLAY 0.617021 (-4315 3985);
PAINT ORANGE (-4315 3985);
FORCEPROP 2 LASTPIN (-4325 3925) $PN CU56
J 0
(-4315 3935);
DISPLAY 0.617021 (-4315 3935);
PAINT ORANGE (-4315 3935);
FORCEPROP 2 LASTPIN (-4325 3875) $PN CU62
J 0
(-4315 3885);
DISPLAY 0.617021 (-4315 3885);
PAINT ORANGE (-4315 3885);
FORCEPROP 2 LASTPIN (-4325 3825) $PN CU68
J 0
(-4315 3835);
DISPLAY 0.617021 (-4315 3835);
PAINT ORANGE (-4315 3835);
FORCEPROP 2 LASTPIN (-4325 3775) $PN CU76
J 0
(-4315 3785);
DISPLAY 0.617021 (-4315 3785);
PAINT ORANGE (-4315 3785);
FORCEPROP 2 LASTPIN (-4325 3725) $PN CU78
J 0
(-4315 3735);
DISPLAY 0.617021 (-4315 3735);
PAINT ORANGE (-4315 3735);
FORCEPROP 2 LASTPIN (-4325 3675) $PN CU80
J 0
(-4315 3685);
DISPLAY 0.617021 (-4315 3685);
PAINT ORANGE (-4315 3685);
FORCEPROP 2 LASTPIN (-4325 3625) $PN CU82
J 0
(-4315 3635);
DISPLAY 0.617021 (-4315 3635);
PAINT ORANGE (-4315 3635);
FORCEPROP 2 LASTPIN (-4325 3575) $PN CU86
J 0
(-4315 3585);
DISPLAY 0.617021 (-4315 3585);
PAINT ORANGE (-4315 3585);
FORCEPROP 2 LASTPIN (-4325 3525) $PN CV1
J 0
(-4315 3535);
DISPLAY 0.617021 (-4315 3535);
PAINT ORANGE (-4315 3535);
FORCEPROP 2 LASTPIN (-4325 3475) $PN H55
J 0
(-4315 3485);
DISPLAY 0.617021 (-4315 3485);
PAINT ORANGE (-4315 3485);
FORCEPROP 2 LASTPIN (-4325 3425) $PN CV17
J 0
(-4315 3435);
DISPLAY 0.617021 (-4315 3435);
PAINT ORANGE (-4315 3435);
FORCEPROP 2 LASTPIN (-4325 3375) $PN CV25
J 0
(-4315 3385);
DISPLAY 0.617021 (-4315 3385);
PAINT ORANGE (-4315 3385);
FORCEPROP 2 LASTPIN (-4325 3325) $PN CV27
J 0
(-4315 3335);
DISPLAY 0.617021 (-4315 3335);
PAINT ORANGE (-4315 3335);
FORCEPROP 2 LASTPIN (-4325 3275) $PN CV31
J 0
(-4315 3285);
DISPLAY 0.617021 (-4315 3285);
PAINT ORANGE (-4315 3285);
FORCEPROP 2 LASTPIN (-4325 3225) $PN CV33
J 0
(-4315 3235);
DISPLAY 0.617021 (-4315 3235);
PAINT ORANGE (-4315 3235);
FORCEPROP 2 LASTPIN (-4325 3175) $PN CV37
J 0
(-4315 3185);
DISPLAY 0.617021 (-4315 3185);
PAINT ORANGE (-4315 3185);
FORCEPROP 2 LASTPIN (-4325 3125) $PN CV39
J 0
(-4315 3135);
DISPLAY 0.617021 (-4315 3135);
PAINT ORANGE (-4315 3135);
FORCEPROP 2 LASTPIN (-4325 3075) $PN CV41
J 0
(-4315 3085);
DISPLAY 0.617021 (-4315 3085);
PAINT ORANGE (-4315 3085);
FORCEPROP 2 LASTPIN (-4325 3025) $PN CV53
J 0
(-4315 3035);
DISPLAY 0.617021 (-4315 3035);
PAINT ORANGE (-4315 3035);
FORCEPROP 2 LASTPIN (-4325 2975) $PN CV55
J 0
(-4315 2985);
DISPLAY 0.617021 (-4315 2985);
PAINT ORANGE (-4315 2985);
FORCEPROP 2 LASTPIN (-4325 2925) $PN CV63
J 0
(-4315 2935);
DISPLAY 0.617021 (-4315 2935);
PAINT ORANGE (-4315 2935);
FORCEPROP 2 LASTPIN (-4325 2875) $PN CV67
J 0
(-4315 2885);
DISPLAY 0.617021 (-4315 2885);
PAINT ORANGE (-4315 2885);
FORCEPROP 2 LASTPIN (-4325 2825) $PN CV73
J 0
(-4315 2835);
DISPLAY 0.617021 (-4315 2835);
PAINT ORANGE (-4315 2835);
FORCEPROP 2 LASTPIN (-4325 2775) $PN CV79
J 0
(-4315 2785);
DISPLAY 0.617021 (-4315 2785);
PAINT ORANGE (-4315 2785);
FORCEPROP 2 LASTPIN (-4325 2725) $PN CV81
J 0
(-4315 2735);
DISPLAY 0.617021 (-4315 2735);
PAINT ORANGE (-4315 2735);
FORCEPROP 2 LASTPIN (-4325 2675) $PN CV83
J 0
(-4315 2685);
DISPLAY 0.617021 (-4315 2685);
PAINT ORANGE (-4315 2685);
FORCEPROP 2 LASTPIN (-4325 2625) $PN CW12
J 0
(-4315 2635);
DISPLAY 0.617021 (-4315 2635);
PAINT ORANGE (-4315 2635);
FORCEPROP 2 LASTPIN (-4325 2575) $PN CW26
J 0
(-4315 2585);
DISPLAY 0.617021 (-4315 2585);
PAINT ORANGE (-4315 2585);
FORCEPROP 2 LASTPIN (-4325 2525) $PN CW32
J 0
(-4315 2535);
DISPLAY 0.617021 (-4315 2535);
PAINT ORANGE (-4315 2535);
FORCEPROP 2 LASTPIN (-4325 2475) $PN CW38
J 0
(-4315 2485);
DISPLAY 0.617021 (-4315 2485);
PAINT ORANGE (-4315 2485);
FORCEPROP 2 LASTPIN (-4325 2425) $PN CW40
J 0
(-4315 2435);
DISPLAY 0.617021 (-4315 2435);
PAINT ORANGE (-4315 2435);
FORCEPROP 2 LASTPIN (-4325 2375) $PN CW42
J 0
(-4315 2385);
DISPLAY 0.617021 (-4315 2385);
PAINT ORANGE (-4315 2385);
FORCEPROP 2 LASTPIN (-4325 2325) $PN CW52
J 0
(-4315 2335);
DISPLAY 0.617021 (-4315 2335);
PAINT ORANGE (-4315 2335);
FORCEPROP 2 LASTPIN (-4325 2275) $PN CW54
J 0
(-4315 2285);
DISPLAY 0.617021 (-4315 2285);
PAINT ORANGE (-4315 2285);
FORCEPROP 2 LASTPIN (-4325 2225) $PN CW64
J 0
(-4315 2235);
DISPLAY 0.617021 (-4315 2235);
PAINT ORANGE (-4315 2235);
FORCEPROP 2 LASTPIN (-4325 2175) $PN CW66
J 0
(-4315 2185);
DISPLAY 0.617021 (-4315 2185);
PAINT ORANGE (-4315 2185);
FORCEPROP 2 LASTPIN (-4325 2125) $PN CW68
J 0
(-4315 2135);
DISPLAY 0.617021 (-4315 2135);
PAINT ORANGE (-4315 2135);
FORCEPROP 2 LASTPIN (-4325 2075) $PN CW74
J 0
(-4315 2085);
DISPLAY 0.617021 (-4315 2085);
PAINT ORANGE (-4315 2085);
FORCEPROP 2 LASTPIN (-4325 2025) $PN CW78
J 0
(-4315 2035);
DISPLAY 0.617021 (-4315 2035);
PAINT ORANGE (-4315 2035);
FORCEPROP 2 LASTPIN (-4325 1975) $PN CW82
J 0
(-4315 1985);
DISPLAY 0.617021 (-4315 1985);
PAINT ORANGE (-4315 1985);
FORCEPROP 2 LASTPIN (-4325 1925) $PN CY1
J 0
(-4315 1935);
DISPLAY 0.617021 (-4315 1935);
PAINT ORANGE (-4315 1935);
FORCEPROP 2 LASTPIN (-4325 1875) $PN CY9
J 0
(-4315 1885);
DISPLAY 0.617021 (-4315 1885);
PAINT ORANGE (-4315 1885);
FORCEPROP 2 LASTPIN (-4325 1825) $PN CY13
J 0
(-4315 1835);
DISPLAY 0.617021 (-4315 1835);
PAINT ORANGE (-4315 1835);
FORCEPROP 2 LASTPIN (-4325 1775) $PN CY15
J 0
(-4315 1785);
DISPLAY 0.617021 (-4315 1785);
PAINT ORANGE (-4315 1785);
FORCEPROP 2 LASTPIN (-4325 1725) $PN CY21
J 0
(-4315 1735);
DISPLAY 0.617021 (-4315 1735);
PAINT ORANGE (-4315 1735);
FORCEPROP 2 LASTPIN (-4325 1675) $PN CY41
J 0
(-4315 1685);
DISPLAY 0.617021 (-4315 1685);
PAINT ORANGE (-4315 1685);
FORCEPROP 2 LASTPIN (-4325 1625) $PN CY45
J 0
(-4315 1635);
DISPLAY 0.617021 (-4315 1635);
PAINT ORANGE (-4315 1635);
FORCEPROP 2 LASTPIN (-4325 1575) $PN CY51
J 0
(-4315 1585);
DISPLAY 0.617021 (-4315 1585);
PAINT ORANGE (-4315 1585);
FORCEPROP 2 LASTPIN (-4325 1525) $PN CY59
J 0
(-4315 1535);
DISPLAY 0.617021 (-4315 1535);
PAINT ORANGE (-4315 1535);
FORCEPROP 2 LASTPIN (-4325 1475) $PN CY61
J 0
(-4315 1485);
DISPLAY 0.617021 (-4315 1485);
PAINT ORANGE (-4315 1485);
FORCEPROP 2 LASTPIN (-4325 1425) $PN CY65
J 0
(-4315 1435);
DISPLAY 0.617021 (-4315 1435);
PAINT ORANGE (-4315 1435);
FORCEPROP 2 LASTPIN (-4325 1375) $PN CY69
J 0
(-4315 1385);
DISPLAY 0.617021 (-4315 1385);
PAINT ORANGE (-4315 1385);
FORCEPROP 2 LASTPIN (-4325 1325) $PN CY75
J 0
(-4315 1335);
DISPLAY 0.617021 (-4315 1335);
PAINT ORANGE (-4315 1335);
FORCEPROP 2 LASTPIN (-4325 1275) $PN CY77
J 0
(-4315 1285);
DISPLAY 0.617021 (-4315 1285);
PAINT ORANGE (-4315 1285);
FORCEPROP 2 LASTPIN (-4325 1225) $PN CY83
J 0
(-4315 1235);
DISPLAY 0.617021 (-4315 1235);
PAINT ORANGE (-4315 1235);
FORCEPROP 2 LASTPIN (-4325 1175) $PN CY85
J 0
(-4315 1185);
DISPLAY 0.617021 (-4315 1185);
PAINT ORANGE (-4315 1185);
FORCEPROP 2 LASTPIN (-4325 1125) $PN DA6
J 0
(-4315 1135);
DISPLAY 0.617021 (-4315 1135);
PAINT ORANGE (-4315 1135);
FORCEPROP 2 LASTPIN (-4325 1075) $PN H53
J 0
(-4315 1085);
DISPLAY 0.617021 (-4315 1085);
PAINT ORANGE (-4315 1085);
FORCEPROP 2 LASTPIN (-4325 1025) $PN DA18
J 0
(-4315 1035);
DISPLAY 0.617021 (-4315 1035);
PAINT ORANGE (-4315 1035);
FORCEPROP 2 LASTPIN (-4325 975) $PN DA26
J 0
(-4315 985);
DISPLAY 0.617021 (-4315 985);
PAINT ORANGE (-4315 985);
FORCEPROP 2 LASTPIN (-4325 925) $PN DA28
J 0
(-4315 935);
DISPLAY 0.617021 (-4315 935);
PAINT ORANGE (-4315 935);
FORCEPROP 2 LASTPIN (-4325 875) $PN DA30
J 0
(-4315 885);
DISPLAY 0.617021 (-4315 885);
PAINT ORANGE (-4315 885);
FORCEPROP 2 LASTPIN (-4325 825) $PN DA32
J 0
(-4315 835);
DISPLAY 0.617021 (-4315 835);
PAINT ORANGE (-4315 835);
FORCEPROP 2 LASTPIN (-4325 775) $PN DA34
J 0
(-4315 785);
DISPLAY 0.617021 (-4315 785);
PAINT ORANGE (-4315 785);
FORCEPROP 2 LASTPIN (-4325 725) $PN DA36
J 0
(-4315 735);
DISPLAY 0.617021 (-4315 735);
PAINT ORANGE (-4315 735);
FORCEPROP 2 LASTPIN (-4325 675) $PN DA38
J 0
(-4315 685);
DISPLAY 0.617021 (-4315 685);
PAINT ORANGE (-4315 685);
FORCEPROP 2 LASTPIN (-4325 625) $PN DA44
J 0
(-4315 635);
DISPLAY 0.617021 (-4315 635);
PAINT ORANGE (-4315 635);
FORCEPROP 2 LASTPIN (-4325 575) $PN DA46
J 0
(-4315 585);
DISPLAY 0.617021 (-4315 585);
PAINT ORANGE (-4315 585);
FORCEPROP 1 LAST PACK_TYPE BGA1
J 0
(-5475 4825);
PAINT SKYBLUE (-5475 4825);
DISPLAY INVISIBLE (-5475 4825);
FORCEPROP 2 LAST SEC_TYPE BGA1
J 0
(-5475 4825);
DISPLAY 1.021277 (-5475 4825);
PAINT ORANGE (-5475 4825);
DISPLAY INVISIBLE (-5475 4825);
FORCEPROP 2 LAST CDS_LIB chpset_lib
J 0
(-4925 2525);
PAINT ORANGE (-4925 2525);
DISPLAY INVISIBLE (-4925 2525);
FORCEPROP 2 LAST SEC 28
J 0
(-5475 4825);
DISPLAY 0.680851 (-5475 4825);
PAINT MONO (-5475 4825);
DISPLAY INVISIBLE (-5475 4825);
FORCEPROP 2 LAST CDS_LOCATION U2D1
J 0
(-5475 4775);
DISPLAY 0.617021 (-5475 4775);
PAINT AQUA (-5475 4775);
DISPLAY INVISIBLE (-5475 4775);
FORCEPROP 1 LAST PATH I18
J 0
(-4925 4725);
PAINT GREEN (-4925 4725);
DISPLAY INVISIBLE (-4925 4725);
FORCEADD SKX_EXT_B..29
(-3050 2525);
FORCEPROP 1 LAST LOCATION U2D1
J 0
(-3600 4775);
DISPLAY 0.617021 (-3600 4775);
PAINT AQUA (-3600 4775);
FORCEPROP 1 LAST PART_NUMBER TBD
J 0
(-3600 375);
DISPLAY 0.617021 (-3600 375);
PAINT BLUE (-3600 375);
FORCEPROP 1 LAST MATERIAL IC
J 0
(-3600 4725);
DISPLAY 0.617021 (-3600 4725);
PAINT SKYBLUE (-3600 4725);
FORCEPROP 2 LASTPIN (-3650 4525) $PN DA48
J 2
(-3660 4535);
DISPLAY 0.617021 (-3660 4535);
PAINT ORANGE (-3660 4535);
FORCEPROP 2 LASTPIN (-3650 4475) $PN DA50
J 2
(-3660 4485);
DISPLAY 0.617021 (-3660 4485);
PAINT ORANGE (-3660 4485);
FORCEPROP 2 LASTPIN (-3650 4425) $PN DA64
J 2
(-3660 4435);
DISPLAY 0.617021 (-3660 4435);
PAINT ORANGE (-3660 4435);
FORCEPROP 2 LASTPIN (-3650 4375) $PN DA70
J 2
(-3660 4385);
DISPLAY 0.617021 (-3660 4385);
PAINT ORANGE (-3660 4385);
FORCEPROP 2 LASTPIN (-3650 4325) $PN DA74
J 2
(-3660 4335);
DISPLAY 0.617021 (-3660 4335);
PAINT ORANGE (-3660 4335);
FORCEPROP 2 LASTPIN (-3650 4275) $PN DA76
J 2
(-3660 4285);
DISPLAY 0.617021 (-3660 4285);
PAINT ORANGE (-3660 4285);
FORCEPROP 2 LASTPIN (-3650 4225) $PN DA78
J 2
(-3660 4235);
DISPLAY 0.617021 (-3660 4235);
PAINT ORANGE (-3660 4235);
FORCEPROP 2 LASTPIN (-3650 4175) $PN DA80
J 2
(-3660 4185);
DISPLAY 0.617021 (-3660 4185);
PAINT ORANGE (-3660 4185);
FORCEPROP 2 LASTPIN (-3650 4125) $PN DB3
J 2
(-3660 4135);
DISPLAY 0.617021 (-3660 4135);
PAINT ORANGE (-3660 4135);
FORCEPROP 2 LASTPIN (-3650 4075) $PN DB13
J 2
(-3660 4085);
DISPLAY 0.617021 (-3660 4085);
PAINT ORANGE (-3660 4085);
FORCEPROP 2 LASTPIN (-3650 4025) $PN DB17
J 2
(-3660 4035);
DISPLAY 0.617021 (-3660 4035);
PAINT ORANGE (-3660 4035);
FORCEPROP 2 LASTPIN (-3650 3975) $PN DB23
J 2
(-3660 3985);
DISPLAY 0.617021 (-3660 3985);
PAINT ORANGE (-3660 3985);
FORCEPROP 2 LASTPIN (-3650 3925) $PN DB25
J 2
(-3660 3935);
DISPLAY 0.617021 (-3660 3935);
PAINT ORANGE (-3660 3935);
FORCEPROP 2 LASTPIN (-3650 3875) $PN DB39
J 2
(-3660 3885);
DISPLAY 0.617021 (-3660 3885);
PAINT ORANGE (-3660 3885);
FORCEPROP 2 LASTPIN (-3650 3825) $PN DB41
J 2
(-3660 3835);
DISPLAY 0.617021 (-3660 3835);
PAINT ORANGE (-3660 3835);
FORCEPROP 2 LASTPIN (-3650 3775) $PN DB47
J 2
(-3660 3785);
DISPLAY 0.617021 (-3660 3785);
PAINT ORANGE (-3660 3785);
FORCEPROP 2 LASTPIN (-3650 3725) $PN DB49
J 2
(-3660 3735);
DISPLAY 0.617021 (-3660 3735);
PAINT ORANGE (-3660 3735);
FORCEPROP 2 LASTPIN (-3650 3675) $PN DB73
J 2
(-3660 3685);
DISPLAY 0.617021 (-3660 3685);
PAINT ORANGE (-3660 3685);
FORCEPROP 2 LASTPIN (-3650 3625) $PN DB77
J 2
(-3660 3635);
DISPLAY 0.617021 (-3660 3635);
PAINT ORANGE (-3660 3635);
FORCEPROP 2 LASTPIN (-3650 3575) $PN DB83
J 2
(-3660 3585);
DISPLAY 0.617021 (-3660 3585);
PAINT ORANGE (-3660 3585);
FORCEPROP 2 LASTPIN (-3650 3525) $PN DB85
J 2
(-3660 3535);
DISPLAY 0.617021 (-3660 3535);
PAINT ORANGE (-3660 3535);
FORCEPROP 2 LASTPIN (-3650 3475) $PN DC14
J 2
(-3660 3485);
DISPLAY 0.617021 (-3660 3485);
PAINT ORANGE (-3660 3485);
FORCEPROP 2 LASTPIN (-3650 3425) $PN DC24
J 2
(-3660 3435);
DISPLAY 0.617021 (-3660 3435);
PAINT ORANGE (-3660 3435);
FORCEPROP 2 LASTPIN (-3650 3375) $PN DC26
J 2
(-3660 3385);
DISPLAY 0.617021 (-3660 3385);
PAINT ORANGE (-3660 3385);
FORCEPROP 2 LASTPIN (-3650 3325) $PN DC32
J 2
(-3660 3335);
DISPLAY 0.617021 (-3660 3335);
PAINT ORANGE (-3660 3335);
FORCEPROP 2 LASTPIN (-3650 3275) $PN DC38
J 2
(-3660 3285);
DISPLAY 0.617021 (-3660 3285);
PAINT ORANGE (-3660 3285);
FORCEPROP 2 LASTPIN (-3650 3225) $PN DC42
J 2
(-3660 3235);
DISPLAY 0.617021 (-3660 3235);
PAINT ORANGE (-3660 3235);
FORCEPROP 2 LASTPIN (-3650 3175) $PN DC64
J 2
(-3660 3185);
DISPLAY 0.617021 (-3660 3185);
PAINT ORANGE (-3660 3185);
FORCEPROP 2 LASTPIN (-3650 3125) $PN DC66
J 2
(-3660 3135);
DISPLAY 0.617021 (-3660 3135);
PAINT ORANGE (-3660 3135);
FORCEPROP 2 LASTPIN (-3650 3075) $PN DC68
J 2
(-3660 3085);
DISPLAY 0.617021 (-3660 3085);
PAINT ORANGE (-3660 3085);
FORCEPROP 2 LASTPIN (-3650 3025) $PN DC70
J 2
(-3660 3035);
DISPLAY 0.617021 (-3660 3035);
PAINT ORANGE (-3660 3035);
FORCEPROP 2 LASTPIN (-3650 2975) $PN DC78
J 2
(-3660 2985);
DISPLAY 0.617021 (-3660 2985);
PAINT ORANGE (-3660 2985);
FORCEPROP 2 LASTPIN (-3650 2925) $PN DC84
J 2
(-3660 2935);
DISPLAY 0.617021 (-3660 2935);
PAINT ORANGE (-3660 2935);
FORCEPROP 2 LASTPIN (-3650 2875) $PN DC86
J 2
(-3660 2885);
DISPLAY 0.617021 (-3660 2885);
PAINT ORANGE (-3660 2885);
FORCEPROP 2 LASTPIN (-3650 2825) $PN DD11
J 2
(-3660 2835);
DISPLAY 0.617021 (-3660 2835);
PAINT ORANGE (-3660 2835);
FORCEPROP 2 LASTPIN (-3650 2775) $PN DD23
J 2
(-3660 2785);
DISPLAY 0.617021 (-3660 2785);
PAINT ORANGE (-3660 2785);
FORCEPROP 2 LASTPIN (-3650 2725) $PN DD27
J 2
(-3660 2735);
DISPLAY 0.617021 (-3660 2735);
PAINT ORANGE (-3660 2735);
FORCEPROP 2 LASTPIN (-3650 2675) $PN DD31
J 2
(-3660 2685);
DISPLAY 0.617021 (-3660 2685);
PAINT ORANGE (-3660 2685);
FORCEPROP 2 LASTPIN (-3650 2625) $PN DD33
J 2
(-3660 2635);
DISPLAY 0.617021 (-3660 2635);
PAINT ORANGE (-3660 2635);
FORCEPROP 2 LASTPIN (-3650 2575) $PN DD37
J 2
(-3660 2585);
DISPLAY 0.617021 (-3660 2585);
PAINT ORANGE (-3660 2585);
FORCEPROP 2 LASTPIN (-3650 2525) $PN DD71
J 2
(-3660 2535);
DISPLAY 0.617021 (-3660 2535);
PAINT ORANGE (-3660 2535);
FORCEPROP 2 LASTPIN (-3650 2475) $PN DD73
J 2
(-3660 2485);
DISPLAY 0.617021 (-3660 2485);
PAINT ORANGE (-3660 2485);
FORCEPROP 2 LASTPIN (-3650 2425) $PN DD75
J 2
(-3660 2435);
DISPLAY 0.617021 (-3660 2435);
PAINT ORANGE (-3660 2435);
FORCEPROP 2 LASTPIN (-3650 2375) $PN DD81
J 2
(-3660 2385);
DISPLAY 0.617021 (-3660 2385);
PAINT ORANGE (-3660 2385);
FORCEPROP 2 LASTPIN (-3650 2325) $PN DD83
J 2
(-3660 2335);
DISPLAY 0.617021 (-3660 2335);
PAINT ORANGE (-3660 2335);
FORCEPROP 2 LASTPIN (-3650 2275) $PN DE6
J 2
(-3660 2285);
DISPLAY 0.617021 (-3660 2285);
PAINT ORANGE (-3660 2285);
FORCEPROP 2 LASTPIN (-3650 2225) $PN DE8
J 2
(-3660 2235);
DISPLAY 0.617021 (-3660 2235);
PAINT ORANGE (-3660 2235);
FORCEPROP 2 LASTPIN (-3650 2175) $PN DE18
J 2
(-3660 2185);
DISPLAY 0.617021 (-3660 2185);
PAINT ORANGE (-3660 2185);
FORCEPROP 2 LASTPIN (-3650 2125) $PN DE20
J 2
(-3660 2135);
DISPLAY 0.617021 (-3660 2135);
PAINT ORANGE (-3660 2135);
FORCEPROP 2 LASTPIN (-3650 2075) $PN DE24
J 2
(-3660 2085);
DISPLAY 0.617021 (-3660 2085);
PAINT ORANGE (-3660 2085);
FORCEPROP 2 LASTPIN (-3650 2025) $PN DE28
J 2
(-3660 2035);
DISPLAY 0.617021 (-3660 2035);
PAINT ORANGE (-3660 2035);
FORCEPROP 2 LASTPIN (-3650 1975) $PN DE30
J 2
(-3660 1985);
DISPLAY 0.617021 (-3660 1985);
PAINT ORANGE (-3660 1985);
FORCEPROP 2 LASTPIN (-3650 1925) $PN DE34
J 2
(-3660 1935);
DISPLAY 0.617021 (-3660 1935);
PAINT ORANGE (-3660 1935);
FORCEPROP 2 LASTPIN (-3650 1875) $PN DE36
J 2
(-3660 1885);
DISPLAY 0.617021 (-3660 1885);
PAINT ORANGE (-3660 1885);
FORCEPROP 2 LASTPIN (-3650 1825) $PN DE64
J 2
(-3660 1835);
DISPLAY 0.617021 (-3660 1835);
PAINT ORANGE (-3660 1835);
FORCEPROP 2 LASTPIN (-3650 1775) $PN DE70
J 2
(-3660 1785);
DISPLAY 0.617021 (-3660 1785);
PAINT ORANGE (-3660 1785);
FORCEPROP 2 LASTPIN (-3650 1725) $PN DE72
J 2
(-3660 1735);
DISPLAY 0.617021 (-3660 1735);
PAINT ORANGE (-3660 1735);
FORCEPROP 2 LASTPIN (-3650 1675) $PN DE78
J 2
(-3660 1685);
DISPLAY 0.617021 (-3660 1685);
PAINT ORANGE (-3660 1685);
FORCEPROP 2 LASTPIN (-3650 1625) $PN DF5
J 2
(-3660 1635);
DISPLAY 0.617021 (-3660 1635);
PAINT ORANGE (-3660 1635);
FORCEPROP 2 LASTPIN (-3650 1575) $PN DF7
J 2
(-3660 1585);
DISPLAY 0.617021 (-3660 1585);
PAINT ORANGE (-3660 1585);
FORCEPROP 2 LASTPIN (-3650 1525) $PN H51
J 2
(-3660 1535);
DISPLAY 0.617021 (-3660 1535);
PAINT ORANGE (-3660 1535);
FORCEPROP 2 LASTPIN (-3650 1475) $PN DF19
J 2
(-3660 1485);
DISPLAY 0.617021 (-3660 1485);
PAINT ORANGE (-3660 1485);
FORCEPROP 2 LASTPIN (-3650 1425) $PN DF29
J 2
(-3660 1435);
DISPLAY 0.617021 (-3660 1435);
PAINT ORANGE (-3660 1435);
FORCEPROP 2 LASTPIN (-3650 1375) $PN DF35
J 2
(-3660 1385);
DISPLAY 0.617021 (-3660 1385);
PAINT ORANGE (-3660 1385);
FORCEPROP 2 LASTPIN (-3650 1325) $PN DF37
J 2
(-3660 1335);
DISPLAY 0.617021 (-3660 1335);
PAINT ORANGE (-3660 1335);
FORCEPROP 2 LASTPIN (-3650 1275) $PN DF39
J 2
(-3660 1285);
DISPLAY 0.617021 (-3660 1285);
PAINT ORANGE (-3660 1285);
FORCEPROP 2 LASTPIN (-3650 1225) $PN DF41
J 2
(-3660 1235);
DISPLAY 0.617021 (-3660 1235);
PAINT ORANGE (-3660 1235);
FORCEPROP 2 LASTPIN (-3650 1175) $PN DF65
J 2
(-3660 1185);
DISPLAY 0.617021 (-3660 1185);
PAINT ORANGE (-3660 1185);
FORCEPROP 2 LASTPIN (-3650 1125) $PN DF69
J 2
(-3660 1135);
DISPLAY 0.617021 (-3660 1135);
PAINT ORANGE (-3660 1135);
FORCEPROP 2 LASTPIN (-3650 1075) $PN DF73
J 2
(-3660 1085);
DISPLAY 0.617021 (-3660 1085);
PAINT ORANGE (-3660 1085);
FORCEPROP 2 LASTPIN (-3650 1025) $PN DF79
J 2
(-3660 1035);
DISPLAY 0.617021 (-3660 1035);
PAINT ORANGE (-3660 1035);
FORCEPROP 2 LASTPIN (-3650 975) $PN DF83
J 2
(-3660 985);
DISPLAY 0.617021 (-3660 985);
PAINT ORANGE (-3660 985);
FORCEPROP 2 LASTPIN (-3650 925) $PN DF85
J 2
(-3660 935);
DISPLAY 0.617021 (-3660 935);
PAINT ORANGE (-3660 935);
FORCEPROP 2 LASTPIN (-3650 875) $PN DG2
J 2
(-3660 885);
DISPLAY 0.617021 (-3660 885);
PAINT ORANGE (-3660 885);
FORCEPROP 2 LASTPIN (-3650 825) $PN H49
J 2
(-3660 835);
DISPLAY 0.617021 (-3660 835);
PAINT ORANGE (-3660 835);
FORCEPROP 2 LASTPIN (-3650 775) $PN DG14
J 2
(-3660 785);
DISPLAY 0.617021 (-3660 785);
PAINT ORANGE (-3660 785);
FORCEPROP 2 LASTPIN (-3650 725) $PN DG16
J 2
(-3660 735);
DISPLAY 0.617021 (-3660 735);
PAINT ORANGE (-3660 735);
FORCEPROP 2 LASTPIN (-3650 675) $PN DG24
J 2
(-3660 685);
DISPLAY 0.617021 (-3660 685);
PAINT ORANGE (-3660 685);
FORCEPROP 2 LASTPIN (-3650 625) $PN DG66
J 2
(-3660 635);
DISPLAY 0.617021 (-3660 635);
PAINT ORANGE (-3660 635);
FORCEPROP 2 LASTPIN (-3650 575) $PN DG68
J 2
(-3660 585);
DISPLAY 0.617021 (-3660 585);
PAINT ORANGE (-3660 585);
FORCEPROP 2 LASTPIN (-2450 4525) $PN DG76
J 0
(-2440 4535);
DISPLAY 0.617021 (-2440 4535);
PAINT ORANGE (-2440 4535);
FORCEPROP 2 LASTPIN (-2450 4475) $PN DG78
J 0
(-2440 4485);
DISPLAY 0.617021 (-2440 4485);
PAINT ORANGE (-2440 4485);
FORCEPROP 2 LASTPIN (-2450 4425) $PN DG80
J 0
(-2440 4435);
DISPLAY 0.617021 (-2440 4435);
PAINT ORANGE (-2440 4435);
FORCEPROP 2 LASTPIN (-2450 4375) $PN DG82
J 0
(-2440 4385);
DISPLAY 0.617021 (-2440 4385);
PAINT ORANGE (-2440 4385);
FORCEPROP 2 LASTPIN (-2450 4325) $PN DH13
J 0
(-2440 4335);
DISPLAY 0.617021 (-2440 4335);
PAINT ORANGE (-2440 4335);
FORCEPROP 2 LASTPIN (-2450 4275) $PN DH15
J 0
(-2440 4285);
DISPLAY 0.617021 (-2440 4285);
PAINT ORANGE (-2440 4285);
FORCEPROP 2 LASTPIN (-2450 4225) $PN DH23
J 0
(-2440 4235);
DISPLAY 0.617021 (-2440 4235);
PAINT ORANGE (-2440 4235);
FORCEPROP 2 LASTPIN (-2450 4175) $PN DH25
J 0
(-2440 4185);
DISPLAY 0.617021 (-2440 4185);
PAINT ORANGE (-2440 4185);
FORCEPROP 2 LASTPIN (-2450 4125) $PN DH27
J 0
(-2440 4135);
DISPLAY 0.617021 (-2440 4135);
PAINT ORANGE (-2440 4135);
FORCEPROP 2 LASTPIN (-2450 4075) $PN DH29
J 0
(-2440 4085);
DISPLAY 0.617021 (-2440 4085);
PAINT ORANGE (-2440 4085);
FORCEPROP 2 LASTPIN (-2450 4025) $PN DH31
J 0
(-2440 4035);
DISPLAY 0.617021 (-2440 4035);
PAINT ORANGE (-2440 4035);
FORCEPROP 2 LASTPIN (-2450 3975) $PN DH33
J 0
(-2440 3985);
DISPLAY 0.617021 (-2440 3985);
PAINT ORANGE (-2440 3985);
FORCEPROP 2 LASTPIN (-2450 3925) $PN DH35
J 0
(-2440 3935);
DISPLAY 0.617021 (-2440 3935);
PAINT ORANGE (-2440 3935);
FORCEPROP 2 LASTPIN (-2450 3875) $PN DH37
J 0
(-2440 3885);
DISPLAY 0.617021 (-2440 3885);
PAINT ORANGE (-2440 3885);
FORCEPROP 2 LASTPIN (-2450 3825) $PN DH41
J 0
(-2440 3835);
DISPLAY 0.617021 (-2440 3835);
PAINT ORANGE (-2440 3835);
FORCEPROP 2 LASTPIN (-2450 3775) $PN DH67
J 0
(-2440 3785);
DISPLAY 0.617021 (-2440 3785);
PAINT ORANGE (-2440 3785);
FORCEPROP 2 LASTPIN (-2450 3725) $PN DH71
J 0
(-2440 3735);
DISPLAY 0.617021 (-2440 3735);
PAINT ORANGE (-2440 3735);
FORCEPROP 2 LASTPIN (-2450 3675) $PN DH73
J 0
(-2440 3685);
DISPLAY 0.617021 (-2440 3685);
PAINT ORANGE (-2440 3685);
FORCEPROP 2 LASTPIN (-2450 3625) $PN DH79
J 0
(-2440 3635);
DISPLAY 0.617021 (-2440 3635);
PAINT ORANGE (-2440 3635);
FORCEPROP 2 LASTPIN (-2450 3575) $PN DH81
J 0
(-2440 3585);
DISPLAY 0.617021 (-2440 3585);
PAINT ORANGE (-2440 3585);
FORCEPROP 2 LASTPIN (-2450 3525) $PN DH83
J 0
(-2440 3535);
DISPLAY 0.617021 (-2440 3535);
PAINT ORANGE (-2440 3535);
FORCEPROP 2 LASTPIN (-2450 3475) $PN DJ2
J 0
(-2440 3485);
DISPLAY 0.617021 (-2440 3485);
PAINT ORANGE (-2440 3485);
FORCEPROP 2 LASTPIN (-2450 3425) $PN DJ10
J 0
(-2440 3435);
DISPLAY 0.617021 (-2440 3435);
PAINT ORANGE (-2440 3435);
FORCEPROP 2 LASTPIN (-2450 3375) $PN H47
J 0
(-2440 3385);
DISPLAY 0.617021 (-2440 3385);
PAINT ORANGE (-2440 3385);
FORCEPROP 2 LASTPIN (-2450 3325) $PN DJ22
J 0
(-2440 3335);
DISPLAY 0.617021 (-2440 3335);
PAINT ORANGE (-2440 3335);
FORCEPROP 2 LASTPIN (-2450 3275) $PN DJ38
J 0
(-2440 3285);
DISPLAY 0.617021 (-2440 3285);
PAINT ORANGE (-2440 3285);
FORCEPROP 2 LASTPIN (-2450 3225) $PN DJ42
J 0
(-2440 3235);
DISPLAY 0.617021 (-2440 3235);
PAINT ORANGE (-2440 3235);
FORCEPROP 2 LASTPIN (-2450 3175) $PN DJ68
J 0
(-2440 3185);
DISPLAY 0.617021 (-2440 3185);
PAINT ORANGE (-2440 3185);
FORCEPROP 2 LASTPIN (-2450 3125) $PN DJ74
J 0
(-2440 3135);
DISPLAY 0.617021 (-2440 3135);
PAINT ORANGE (-2440 3135);
FORCEPROP 2 LASTPIN (-2450 3075) $PN DJ78
J 0
(-2440 3085);
DISPLAY 0.617021 (-2440 3085);
PAINT ORANGE (-2440 3085);
FORCEPROP 2 LASTPIN (-2450 3025) $PN DJ82
J 0
(-2440 3035);
DISPLAY 0.617021 (-2440 3035);
PAINT ORANGE (-2440 3035);
FORCEPROP 2 LASTPIN (-2450 2975) $PN DJ84
J 0
(-2440 2985);
DISPLAY 0.617021 (-2440 2985);
PAINT ORANGE (-2440 2985);
FORCEPROP 2 LASTPIN (-2450 2925) $PN DK7
J 0
(-2440 2935);
DISPLAY 0.617021 (-2440 2935);
PAINT ORANGE (-2440 2935);
FORCEPROP 2 LASTPIN (-2450 2875) $PN DK23
J 0
(-2440 2885);
DISPLAY 0.617021 (-2440 2885);
PAINT ORANGE (-2440 2885);
FORCEPROP 2 LASTPIN (-2450 2825) $PN DK29
J 0
(-2440 2835);
DISPLAY 0.617021 (-2440 2835);
PAINT ORANGE (-2440 2835);
FORCEPROP 2 LASTPIN (-2450 2775) $PN DK35
J 0
(-2440 2785);
DISPLAY 0.617021 (-2440 2785);
PAINT ORANGE (-2440 2785);
FORCEPROP 2 LASTPIN (-2450 2725) $PN DK39
J 0
(-2440 2735);
DISPLAY 0.617021 (-2440 2735);
PAINT ORANGE (-2440 2735);
FORCEPROP 2 LASTPIN (-2450 2675) $PN DK41
J 0
(-2440 2685);
DISPLAY 0.617021 (-2440 2685);
PAINT ORANGE (-2440 2685);
FORCEPROP 2 LASTPIN (-2450 2625) $PN DK73
J 0
(-2440 2635);
DISPLAY 0.617021 (-2440 2635);
PAINT ORANGE (-2440 2635);
FORCEPROP 2 LASTPIN (-2450 2575) $PN DK75
J 0
(-2440 2585);
DISPLAY 0.617021 (-2440 2585);
PAINT ORANGE (-2440 2585);
FORCEPROP 2 LASTPIN (-2450 2525) $PN DK77
J 0
(-2440 2535);
DISPLAY 0.617021 (-2440 2535);
PAINT ORANGE (-2440 2535);
FORCEPROP 2 LASTPIN (-2450 2475) $PN DK83
J 0
(-2440 2485);
DISPLAY 0.617021 (-2440 2485);
PAINT ORANGE (-2440 2485);
FORCEPROP 2 LASTPIN (-2450 2425) $PN DK85
J 0
(-2440 2435);
DISPLAY 0.617021 (-2440 2435);
PAINT ORANGE (-2440 2435);
FORCEPROP 2 LASTPIN (-2450 2375) $PN DL16
J 0
(-2440 2385);
DISPLAY 0.617021 (-2440 2385);
PAINT ORANGE (-2440 2385);
FORCEPROP 2 LASTPIN (-2450 2325) $PN DL18
J 0
(-2440 2335);
DISPLAY 0.617021 (-2440 2335);
PAINT ORANGE (-2440 2335);
FORCEPROP 2 LASTPIN (-2450 2275) $PN DL4
J 0
(-2440 2285);
DISPLAY 0.617021 (-2440 2285);
PAINT ORANGE (-2440 2285);
FORCEPROP 2 LASTPIN (-2450 2225) $PN DL22
J 0
(-2440 2235);
DISPLAY 0.617021 (-2440 2235);
PAINT ORANGE (-2440 2235);
FORCEPROP 2 LASTPIN (-2450 2175) $PN DL24
J 0
(-2440 2185);
DISPLAY 0.617021 (-2440 2185);
PAINT ORANGE (-2440 2185);
FORCEPROP 2 LASTPIN (-2450 2125) $PN DL28
J 0
(-2440 2135);
DISPLAY 0.617021 (-2440 2135);
PAINT ORANGE (-2440 2135);
FORCEPROP 2 LASTPIN (-2450 2075) $PN DL30
J 0
(-2440 2085);
DISPLAY 0.617021 (-2440 2085);
PAINT ORANGE (-2440 2085);
FORCEPROP 2 LASTPIN (-2450 2025) $PN DL34
J 0
(-2440 2035);
DISPLAY 0.617021 (-2440 2035);
PAINT ORANGE (-2440 2035);
FORCEPROP 2 LASTPIN (-2450 1975) $PN DL36
J 0
(-2440 1985);
DISPLAY 0.617021 (-2440 1985);
PAINT ORANGE (-2440 1985);
FORCEPROP 2 LASTPIN (-2450 1925) $PN DL40
J 0
(-2440 1935);
DISPLAY 0.617021 (-2440 1935);
PAINT ORANGE (-2440 1935);
FORCEPROP 2 LASTPIN (-2450 1875) $PN DL68
J 0
(-2440 1885);
DISPLAY 0.617021 (-2440 1885);
PAINT ORANGE (-2440 1885);
FORCEPROP 2 LASTPIN (-2450 1825) $PN DL70
J 0
(-2440 1835);
DISPLAY 0.617021 (-2440 1835);
PAINT ORANGE (-2440 1835);
FORCEPROP 2 LASTPIN (-2450 1775) $PN DL74
J 0
(-2440 1785);
DISPLAY 0.617021 (-2440 1785);
PAINT ORANGE (-2440 1785);
FORCEPROP 2 LASTPIN (-2450 1725) $PN DL76
J 0
(-2440 1735);
DISPLAY 0.617021 (-2440 1735);
PAINT ORANGE (-2440 1735);
FORCEPROP 2 LASTPIN (-2450 1675) $PN DL78
J 0
(-2440 1685);
DISPLAY 0.617021 (-2440 1685);
PAINT ORANGE (-2440 1685);
FORCEPROP 2 LASTPIN (-2450 1625) $PN DL80
J 0
(-2440 1635);
DISPLAY 0.617021 (-2440 1635);
PAINT ORANGE (-2440 1635);
FORCEPROP 2 LASTPIN (-2450 1575) $PN DM15
J 0
(-2440 1585);
DISPLAY 0.617021 (-2440 1585);
PAINT ORANGE (-2440 1585);
FORCEPROP 2 LASTPIN (-2450 1525) $PN H45
J 0
(-2440 1535);
DISPLAY 0.617021 (-2440 1535);
PAINT ORANGE (-2440 1535);
FORCEPROP 2 LASTPIN (-2450 1475) $PN DM25
J 0
(-2440 1485);
DISPLAY 0.617021 (-2440 1485);
PAINT ORANGE (-2440 1485);
FORCEPROP 2 LASTPIN (-2450 1425) $PN DM27
J 0
(-2440 1435);
DISPLAY 0.617021 (-2440 1435);
PAINT ORANGE (-2440 1435);
FORCEPROP 2 LASTPIN (-2450 1375) $PN DM31
J 0
(-2440 1385);
DISPLAY 0.617021 (-2440 1385);
PAINT ORANGE (-2440 1385);
FORCEPROP 2 LASTPIN (-2450 1325) $PN DM33
J 0
(-2440 1335);
DISPLAY 0.617021 (-2440 1335);
PAINT ORANGE (-2440 1335);
FORCEPROP 2 LASTPIN (-2450 1275) $PN DM37
J 0
(-2440 1285);
DISPLAY 0.617021 (-2440 1285);
PAINT ORANGE (-2440 1285);
FORCEPROP 2 LASTPIN (-2450 1225) $PN DM39
J 0
(-2440 1235);
DISPLAY 0.617021 (-2440 1235);
PAINT ORANGE (-2440 1235);
FORCEPROP 2 LASTPIN (-2450 1175) $PN DM65
J 0
(-2440 1185);
DISPLAY 0.617021 (-2440 1185);
PAINT ORANGE (-2440 1185);
FORCEPROP 2 LASTPIN (-2450 1125) $PN DM73
J 0
(-2440 1135);
DISPLAY 0.617021 (-2440 1135);
PAINT ORANGE (-2440 1135);
FORCEPROP 2 LASTPIN (-2450 1075) $PN DM77
J 0
(-2440 1085);
DISPLAY 0.617021 (-2440 1085);
PAINT ORANGE (-2440 1085);
FORCEPROP 2 LASTPIN (-2450 1025) $PN DM83
J 0
(-2440 1035);
DISPLAY 0.617021 (-2440 1035);
PAINT ORANGE (-2440 1035);
FORCEPROP 2 LASTPIN (-2450 975) $PN DN2
J 0
(-2440 985);
DISPLAY 0.617021 (-2440 985);
PAINT ORANGE (-2440 985);
FORCEPROP 2 LASTPIN (-2450 925) $PN BH17
J 0
(-2440 935);
DISPLAY 0.617021 (-2440 935);
PAINT ORANGE (-2440 935);
FORCEPROP 2 LASTPIN (-2450 875) $PN DN12
J 0
(-2440 885);
DISPLAY 0.617021 (-2440 885);
PAINT ORANGE (-2440 885);
FORCEPROP 2 LASTPIN (-2450 825) $PN DN22
J 0
(-2440 835);
DISPLAY 0.617021 (-2440 835);
PAINT ORANGE (-2440 835);
FORCEPROP 2 LASTPIN (-2450 775) $PN DN26
J 0
(-2440 785);
DISPLAY 0.617021 (-2440 785);
PAINT ORANGE (-2440 785);
FORCEPROP 2 LASTPIN (-2450 725) $PN DN32
J 0
(-2440 735);
DISPLAY 0.617021 (-2440 735);
PAINT ORANGE (-2440 735);
FORCEPROP 2 LASTPIN (-2450 675) $PN DN38
J 0
(-2440 685);
DISPLAY 0.617021 (-2440 685);
PAINT ORANGE (-2440 685);
FORCEPROP 2 LASTPIN (-2450 625) $PN DN68
J 0
(-2440 635);
DISPLAY 0.617021 (-2440 635);
PAINT ORANGE (-2440 635);
FORCEPROP 2 LASTPIN (-2450 575) $PN DN72
J 0
(-2440 585);
DISPLAY 0.617021 (-2440 585);
PAINT ORANGE (-2440 585);
FORCEPROP 1 LAST PACK_TYPE BGA1
J 0
(-3600 4825);
PAINT SKYBLUE (-3600 4825);
DISPLAY INVISIBLE (-3600 4825);
FORCEPROP 2 LAST SEC_TYPE BGA1
J 0
(-3600 4825);
DISPLAY 1.021277 (-3600 4825);
PAINT ORANGE (-3600 4825);
DISPLAY INVISIBLE (-3600 4825);
FORCEPROP 2 LAST CDS_LIB chpset_lib
J 0
(-3050 2525);
PAINT ORANGE (-3050 2525);
DISPLAY INVISIBLE (-3050 2525);
FORCEPROP 2 LAST SEC 29
J 0
(-3600 4825);
DISPLAY 0.680851 (-3600 4825);
PAINT MONO (-3600 4825);
DISPLAY INVISIBLE (-3600 4825);
FORCEPROP 2 LAST CDS_LOCATION U2D1
J 0
(-3600 4775);
DISPLAY 0.617021 (-3600 4775);
PAINT AQUA (-3600 4775);
DISPLAY INVISIBLE (-3600 4775);
FORCEPROP 1 LAST PATH I19
J 0
(-3050 4725);
PAINT GREEN (-3050 4725);
DISPLAY INVISIBLE (-3050 4725);
FORCEADD SKX_EXT_B..30
(-1225 2550);
FORCEPROP 1 LAST LOCATION U2D1
J 0
(-1775 4800);
DISPLAY 0.617021 (-1775 4800);
PAINT AQUA (-1775 4800);
FORCEPROP 1 LAST PART_NUMBER TBD
J 0
(-1775 400);
DISPLAY 0.617021 (-1775 400);
PAINT BLUE (-1775 400);
FORCEPROP 1 LAST MATERIAL IC
J 0
(-1775 4750);
DISPLAY 0.617021 (-1775 4750);
PAINT SKYBLUE (-1775 4750);
FORCEPROP 2 LASTPIN (-1825 4550) $PN DN78
J 2
(-1835 4560);
DISPLAY 0.617021 (-1835 4560);
PAINT ORANGE (-1835 4560);
FORCEPROP 2 LASTPIN (-1825 4500) $PN DP67
J 2
(-1835 4510);
DISPLAY 0.617021 (-1835 4510);
PAINT ORANGE (-1835 4510);
FORCEPROP 2 LASTPIN (-1825 4450) $PN DP69
J 2
(-1835 4460);
DISPLAY 0.617021 (-1835 4460);
PAINT ORANGE (-1835 4460);
FORCEPROP 2 LASTPIN (-1825 4400) $PN DP71
J 2
(-1835 4410);
DISPLAY 0.617021 (-1835 4410);
PAINT ORANGE (-1835 4410);
FORCEPROP 2 LASTPIN (-1825 4350) $PN DP81
J 2
(-1835 4360);
DISPLAY 0.617021 (-1835 4360);
PAINT ORANGE (-1835 4360);
FORCEPROP 2 LASTPIN (-1825 4300) $PN DP83
J 2
(-1835 4310);
DISPLAY 0.617021 (-1835 4310);
PAINT ORANGE (-1835 4310);
FORCEPROP 2 LASTPIN (-1825 4250) $PN BR26
J 2
(-1835 4260);
DISPLAY 0.617021 (-1835 4260);
PAINT ORANGE (-1835 4260);
FORCEPROP 2 LASTPIN (-1825 4200) $PN DR6
J 2
(-1835 4210);
DISPLAY 0.617021 (-1835 4210);
PAINT ORANGE (-1835 4210);
FORCEPROP 2 LASTPIN (-1825 4150) $PN CA20
J 2
(-1835 4160);
DISPLAY 0.617021 (-1835 4160);
PAINT ORANGE (-1835 4160);
FORCEPROP 2 LASTPIN (-1825 4100) $PN CL22
J 2
(-1835 4110);
DISPLAY 0.617021 (-1835 4110);
PAINT ORANGE (-1835 4110);
FORCEPROP 2 LASTPIN (-1825 4050) $PN DR20
J 2
(-1835 4060);
DISPLAY 0.617021 (-1835 4060);
PAINT ORANGE (-1835 4060);
FORCEPROP 2 LASTPIN (-1825 4000) $PN DR22
J 2
(-1835 4010);
DISPLAY 0.617021 (-1835 4010);
PAINT ORANGE (-1835 4010);
FORCEPROP 2 LASTPIN (-1825 3950) $PN DR24
J 2
(-1835 3960);
DISPLAY 0.617021 (-1835 3960);
PAINT ORANGE (-1835 3960);
FORCEPROP 2 LASTPIN (-1825 3900) $PN DR26
J 2
(-1835 3910);
DISPLAY 0.617021 (-1835 3910);
PAINT ORANGE (-1835 3910);
FORCEPROP 2 LASTPIN (-1825 3850) $PN DR28
J 2
(-1835 3860);
DISPLAY 0.617021 (-1835 3860);
PAINT ORANGE (-1835 3860);
FORCEPROP 2 LASTPIN (-1825 3800) $PN DR30
J 2
(-1835 3810);
DISPLAY 0.617021 (-1835 3810);
PAINT ORANGE (-1835 3810);
FORCEPROP 2 LASTPIN (-1825 3750) $PN DR32
J 2
(-1835 3760);
DISPLAY 0.617021 (-1835 3760);
PAINT ORANGE (-1835 3760);
FORCEPROP 2 LASTPIN (-1825 3700) $PN DR34
J 2
(-1835 3710);
DISPLAY 0.617021 (-1835 3710);
PAINT ORANGE (-1835 3710);
FORCEPROP 2 LASTPIN (-1825 3650) $PN DR36
J 2
(-1835 3660);
DISPLAY 0.617021 (-1835 3660);
PAINT ORANGE (-1835 3660);
FORCEPROP 2 LASTPIN (-1825 3600) $PN DR38
J 2
(-1835 3610);
DISPLAY 0.617021 (-1835 3610);
PAINT ORANGE (-1835 3610);
FORCEPROP 2 LASTPIN (-1825 3550) $PN DR40
J 2
(-1835 3560);
DISPLAY 0.617021 (-1835 3560);
PAINT ORANGE (-1835 3560);
FORCEPROP 2 LASTPIN (-1825 3500) $PN DR42
J 2
(-1835 3510);
DISPLAY 0.617021 (-1835 3510);
PAINT ORANGE (-1835 3510);
FORCEPROP 2 LASTPIN (-1825 3450) $PN DR66
J 2
(-1835 3460);
DISPLAY 0.617021 (-1835 3460);
PAINT ORANGE (-1835 3460);
FORCEPROP 2 LASTPIN (-1825 3400) $PN DR68
J 2
(-1835 3410);
DISPLAY 0.617021 (-1835 3410);
PAINT ORANGE (-1835 3410);
FORCEPROP 2 LASTPIN (-1825 3350) $PN DR70
J 2
(-1835 3360);
DISPLAY 0.617021 (-1835 3360);
PAINT ORANGE (-1835 3360);
FORCEPROP 2 LASTPIN (-1825 3300) $PN DR72
J 2
(-1835 3310);
DISPLAY 0.617021 (-1835 3310);
PAINT ORANGE (-1835 3310);
FORCEPROP 2 LASTPIN (-1825 3250) $PN DR74
J 2
(-1835 3260);
DISPLAY 0.617021 (-1835 3260);
PAINT ORANGE (-1835 3260);
FORCEPROP 2 LASTPIN (-1825 3200) $PN DR76
J 2
(-1835 3210);
DISPLAY 0.617021 (-1835 3210);
PAINT ORANGE (-1835 3210);
FORCEPROP 2 LASTPIN (-1825 3150) $PN DR78
J 2
(-1835 3160);
DISPLAY 0.617021 (-1835 3160);
PAINT ORANGE (-1835 3160);
FORCEPROP 2 LASTPIN (-1825 3100) $PN DT3
J 2
(-1835 3110);
DISPLAY 0.617021 (-1835 3110);
PAINT ORANGE (-1835 3110);
FORCEPROP 2 LASTPIN (-1825 3050) $PN DT17
J 2
(-1835 3060);
DISPLAY 0.617021 (-1835 3060);
PAINT ORANGE (-1835 3060);
FORCEPROP 2 LASTPIN (-1825 3000) $PN DH21
J 2
(-1835 3010);
DISPLAY 0.617021 (-1835 3010);
PAINT ORANGE (-1835 3010);
FORCEPROP 2 LASTPIN (-1825 2950) $PN DT65
J 2
(-1835 2960);
DISPLAY 0.617021 (-1835 2960);
PAINT ORANGE (-1835 2960);
FORCEPROP 2 LASTPIN (-1825 2900) $PN DT69
J 2
(-1835 2910);
DISPLAY 0.617021 (-1835 2910);
PAINT ORANGE (-1835 2910);
FORCEPROP 2 LASTPIN (-1825 2850) $PN DT79
J 2
(-1835 2860);
DISPLAY 0.617021 (-1835 2860);
PAINT ORANGE (-1835 2860);
FORCEPROP 2 LASTPIN (-1825 2800) $PN DT83
J 2
(-1835 2810);
DISPLAY 0.617021 (-1835 2810);
PAINT ORANGE (-1835 2810);
FORCEPROP 2 LASTPIN (-1825 2750) $PN DT85
J 2
(-1835 2760);
DISPLAY 0.617021 (-1835 2760);
PAINT ORANGE (-1835 2760);
FORCEPROP 2 LASTPIN (-1825 2700) $PN DU10
J 2
(-1835 2710);
DISPLAY 0.617021 (-1835 2710);
PAINT ORANGE (-1835 2710);
FORCEPROP 2 LASTPIN (-1825 2650) $PN DU14
J 2
(-1835 2660);
DISPLAY 0.617021 (-1835 2660);
PAINT ORANGE (-1835 2660);
FORCEPROP 2 LASTPIN (-1825 2600) $PN CN14
J 2
(-1835 2610);
DISPLAY 0.617021 (-1835 2610);
PAINT ORANGE (-1835 2610);
FORCEPROP 2 LASTPIN (-1825 2550) $PN DU22
J 2
(-1835 2560);
DISPLAY 0.617021 (-1835 2560);
PAINT ORANGE (-1835 2560);
FORCEPROP 2 LASTPIN (-1825 2500) $PN DU26
J 2
(-1835 2510);
DISPLAY 0.617021 (-1835 2510);
PAINT ORANGE (-1835 2510);
FORCEPROP 2 LASTPIN (-1825 2450) $PN DU32
J 2
(-1835 2460);
DISPLAY 0.617021 (-1835 2460);
PAINT ORANGE (-1835 2460);
FORCEPROP 2 LASTPIN (-1825 2400) $PN DU38
J 2
(-1835 2410);
DISPLAY 0.617021 (-1835 2410);
PAINT ORANGE (-1835 2410);
FORCEPROP 2 LASTPIN (-1825 2350) $PN DU70
J 2
(-1835 2360);
DISPLAY 0.617021 (-1835 2360);
PAINT ORANGE (-1835 2360);
FORCEPROP 2 LASTPIN (-1825 2300) $PN DU72
J 2
(-1835 2310);
DISPLAY 0.617021 (-1835 2310);
PAINT ORANGE (-1835 2310);
FORCEPROP 2 LASTPIN (-1825 2250) $PN DU78
J 2
(-1835 2260);
DISPLAY 0.617021 (-1835 2260);
PAINT ORANGE (-1835 2260);
FORCEPROP 2 LASTPIN (-1825 2200) $PN DU80
J 2
(-1835 2210);
DISPLAY 0.617021 (-1835 2210);
PAINT ORANGE (-1835 2210);
FORCEPROP 2 LASTPIN (-1825 2150) $PN DU82
J 2
(-1835 2160);
DISPLAY 0.617021 (-1835 2160);
PAINT ORANGE (-1835 2160);
FORCEPROP 2 LASTPIN (-1825 2100) $PN DU84
J 2
(-1835 2110);
DISPLAY 0.617021 (-1835 2110);
PAINT ORANGE (-1835 2110);
FORCEPROP 2 LASTPIN (-1825 2050) $PN DV21
J 2
(-1835 2060);
DISPLAY 0.617021 (-1835 2060);
PAINT ORANGE (-1835 2060);
FORCEPROP 2 LASTPIN (-1825 2000) $PN DV25
J 2
(-1835 2010);
DISPLAY 0.617021 (-1835 2010);
PAINT ORANGE (-1835 2010);
FORCEPROP 2 LASTPIN (-1825 1950) $PN DV27
J 2
(-1835 1960);
DISPLAY 0.617021 (-1835 1960);
PAINT ORANGE (-1835 1960);
FORCEPROP 2 LASTPIN (-1825 1900) $PN DV31
J 2
(-1835 1910);
DISPLAY 0.617021 (-1835 1910);
PAINT ORANGE (-1835 1910);
FORCEPROP 2 LASTPIN (-1825 1850) $PN DV33
J 2
(-1835 1860);
DISPLAY 0.617021 (-1835 1860);
PAINT ORANGE (-1835 1860);
FORCEPROP 2 LASTPIN (-1825 1800) $PN DV37
J 2
(-1835 1810);
DISPLAY 0.617021 (-1835 1810);
PAINT ORANGE (-1835 1810);
FORCEPROP 2 LASTPIN (-1825 1750) $PN DV39
J 2
(-1835 1760);
DISPLAY 0.617021 (-1835 1760);
PAINT ORANGE (-1835 1760);
FORCEPROP 2 LASTPIN (-1825 1700) $PN DV73
J 2
(-1835 1710);
DISPLAY 0.617021 (-1835 1710);
PAINT ORANGE (-1835 1710);
FORCEPROP 2 LASTPIN (-1825 1650) $PN DV77
J 2
(-1835 1660);
DISPLAY 0.617021 (-1835 1660);
PAINT ORANGE (-1835 1660);
FORCEPROP 2 LASTPIN (-1825 1600) $PN DV81
J 2
(-1835 1610);
DISPLAY 0.617021 (-1835 1610);
PAINT ORANGE (-1835 1610);
FORCEPROP 2 LASTPIN (-1825 1550) $PN DW12
J 2
(-1835 1560);
DISPLAY 0.617021 (-1835 1560);
PAINT ORANGE (-1835 1560);
FORCEPROP 2 LASTPIN (-1825 1500) $PN DW20
J 2
(-1835 1510);
DISPLAY 0.617021 (-1835 1510);
PAINT ORANGE (-1835 1510);
FORCEPROP 2 LASTPIN (-1825 1450) $PN DW24
J 2
(-1835 1460);
DISPLAY 0.617021 (-1835 1460);
PAINT ORANGE (-1835 1460);
FORCEPROP 2 LASTPIN (-1825 1400) $PN DW28
J 2
(-1835 1410);
DISPLAY 0.617021 (-1835 1410);
PAINT ORANGE (-1835 1410);
FORCEPROP 2 LASTPIN (-1825 1350) $PN DW30
J 2
(-1835 1360);
DISPLAY 0.617021 (-1835 1360);
PAINT ORANGE (-1835 1360);
FORCEPROP 2 LASTPIN (-1825 1300) $PN DW34
J 2
(-1835 1310);
DISPLAY 0.617021 (-1835 1310);
PAINT ORANGE (-1835 1310);
FORCEPROP 2 LASTPIN (-1825 1250) $PN DW36
J 2
(-1835 1260);
DISPLAY 0.617021 (-1835 1260);
PAINT ORANGE (-1835 1260);
FORCEPROP 2 LASTPIN (-1825 1200) $PN DW40
J 2
(-1835 1210);
DISPLAY 0.617021 (-1835 1210);
PAINT ORANGE (-1835 1210);
FORCEPROP 2 LASTPIN (-1825 1150) $PN DW64
J 2
(-1835 1160);
DISPLAY 0.617021 (-1835 1160);
PAINT ORANGE (-1835 1160);
FORCEPROP 2 LASTPIN (-1825 1100) $PN DW66
J 2
(-1835 1110);
DISPLAY 0.617021 (-1835 1110);
PAINT ORANGE (-1835 1110);
FORCEPROP 2 LASTPIN (-1825 1050) $PN DW68
J 2
(-1835 1060);
DISPLAY 0.617021 (-1835 1060);
PAINT ORANGE (-1835 1060);
FORCEPROP 2 LASTPIN (-1825 1000) $PN DW70
J 2
(-1835 1010);
DISPLAY 0.617021 (-1835 1010);
PAINT ORANGE (-1835 1010);
FORCEPROP 2 LASTPIN (-1825 950) $PN DW72
J 2
(-1835 960);
DISPLAY 0.617021 (-1835 960);
PAINT ORANGE (-1835 960);
FORCEPROP 2 LASTPIN (-1825 900) $PN DW74
J 2
(-1835 910);
DISPLAY 0.617021 (-1835 910);
PAINT ORANGE (-1835 910);
FORCEPROP 2 LASTPIN (-1825 850) $PN DW76
J 2
(-1835 860);
DISPLAY 0.617021 (-1835 860);
PAINT ORANGE (-1835 860);
FORCEPROP 2 LASTPIN (-1825 800) $PN DW8
J 2
(-1835 810);
DISPLAY 0.617021 (-1835 810);
PAINT ORANGE (-1835 810);
FORCEPROP 2 LASTPIN (-1825 750) $PN DW82
J 2
(-1835 760);
DISPLAY 0.617021 (-1835 760);
PAINT ORANGE (-1835 760);
FORCEPROP 2 LASTPIN (-1825 700) $PN DW84
J 2
(-1835 710);
DISPLAY 0.617021 (-1835 710);
PAINT ORANGE (-1835 710);
FORCEPROP 2 LASTPIN (-1825 650) $PN DY5
J 2
(-1835 660);
DISPLAY 0.617021 (-1835 660);
PAINT ORANGE (-1835 660);
FORCEPROP 2 LASTPIN (-1825 600) $PN DY19
J 2
(-1835 610);
DISPLAY 0.617021 (-1835 610);
PAINT ORANGE (-1835 610);
FORCEPROP 2 LASTPIN (-625 4550) $PN DY23
J 0
(-615 4560);
DISPLAY 0.617021 (-615 4560);
PAINT ORANGE (-615 4560);
FORCEPROP 2 LASTPIN (-625 4500) $PN DY29
J 0
(-615 4510);
DISPLAY 0.617021 (-615 4510);
PAINT ORANGE (-615 4510);
FORCEPROP 2 LASTPIN (-625 4450) $PN DY35
J 0
(-615 4460);
DISPLAY 0.617021 (-615 4460);
PAINT ORANGE (-615 4460);
FORCEPROP 2 LASTPIN (-625 4400) $PN DY41
J 0
(-615 4410);
DISPLAY 0.617021 (-615 4410);
PAINT ORANGE (-615 4410);
FORCEPROP 2 LASTPIN (-625 4350) $PN DY71
J 0
(-615 4360);
DISPLAY 0.617021 (-615 4360);
PAINT ORANGE (-615 4360);
FORCEPROP 2 LASTPIN (-625 4300) $PN DY75
J 0
(-615 4310);
DISPLAY 0.617021 (-615 4310);
PAINT ORANGE (-615 4310);
FORCEPROP 2 LASTPIN (-625 4250) $PN EA6
J 0
(-615 4260);
DISPLAY 0.617021 (-615 4260);
PAINT ORANGE (-615 4260);
FORCEPROP 2 LASTPIN (-625 4200) $PN J16
J 0
(-615 4210);
DISPLAY 0.617021 (-615 4210);
PAINT ORANGE (-615 4210);
FORCEPROP 2 LASTPIN (-625 4150) $PN EA16
J 0
(-615 4160);
DISPLAY 0.617021 (-615 4160);
PAINT ORANGE (-615 4160);
FORCEPROP 2 LASTPIN (-625 4100) $PN EA20
J 0
(-615 4110);
DISPLAY 0.617021 (-615 4110);
PAINT ORANGE (-615 4110);
FORCEPROP 2 LASTPIN (-625 4050) $PN EA22
J 0
(-615 4060);
DISPLAY 0.617021 (-615 4060);
PAINT ORANGE (-615 4060);
FORCEPROP 2 LASTPIN (-625 4000) $PN EA42
J 0
(-615 4010);
DISPLAY 0.617021 (-615 4010);
PAINT ORANGE (-615 4010);
FORCEPROP 2 LASTPIN (-625 3950) $PN EA64
J 0
(-615 3960);
DISPLAY 0.617021 (-615 3960);
PAINT ORANGE (-615 3960);
FORCEPROP 2 LASTPIN (-625 3900) $PN EA70
J 0
(-615 3910);
DISPLAY 0.617021 (-615 3910);
PAINT ORANGE (-615 3910);
FORCEPROP 2 LASTPIN (-625 3850) $PN EA76
J 0
(-615 3860);
DISPLAY 0.617021 (-615 3860);
PAINT ORANGE (-615 3860);
FORCEPROP 2 LASTPIN (-625 3800) $PN EA78
J 0
(-615 3810);
DISPLAY 0.617021 (-615 3810);
PAINT ORANGE (-615 3810);
FORCEPROP 2 LASTPIN (-625 3750) $PN EA80
J 0
(-615 3760);
DISPLAY 0.617021 (-615 3760);
PAINT ORANGE (-615 3760);
FORCEPROP 2 LASTPIN (-625 3700) $PN EA82
J 0
(-615 3710);
DISPLAY 0.617021 (-615 3710);
PAINT ORANGE (-615 3710);
FORCEPROP 2 LASTPIN (-625 3650) $PN EB13
J 0
(-615 3660);
DISPLAY 0.617021 (-615 3660);
PAINT ORANGE (-615 3660);
FORCEPROP 2 LASTPIN (-625 3600) $PN BR18
J 0
(-615 3610);
DISPLAY 0.617021 (-615 3610);
PAINT ORANGE (-615 3610);
FORCEPROP 2 LASTPIN (-625 3550) $PN EB23
J 0
(-615 3560);
DISPLAY 0.617021 (-615 3560);
PAINT ORANGE (-615 3560);
FORCEPROP 2 LASTPIN (-625 3500) $PN EB25
J 0
(-615 3510);
DISPLAY 0.617021 (-615 3510);
PAINT ORANGE (-615 3510);
FORCEPROP 2 LASTPIN (-625 3450) $PN EB27
J 0
(-615 3460);
DISPLAY 0.617021 (-615 3460);
PAINT ORANGE (-615 3460);
FORCEPROP 2 LASTPIN (-625 3400) $PN EB29
J 0
(-615 3410);
DISPLAY 0.617021 (-615 3410);
PAINT ORANGE (-615 3410);
FORCEPROP 2 LASTPIN (-625 3350) $PN EB31
J 0
(-615 3360);
DISPLAY 0.617021 (-615 3360);
PAINT ORANGE (-615 3360);
FORCEPROP 2 LASTPIN (-625 3300) $PN EB33
J 0
(-615 3310);
DISPLAY 0.617021 (-615 3310);
PAINT ORANGE (-615 3310);
FORCEPROP 2 LASTPIN (-625 3250) $PN EB35
J 0
(-615 3260);
DISPLAY 0.617021 (-615 3260);
PAINT ORANGE (-615 3260);
FORCEPROP 2 LASTPIN (-625 3200) $PN EB37
J 0
(-615 3210);
DISPLAY 0.617021 (-615 3210);
PAINT ORANGE (-615 3210);
FORCEPROP 2 LASTPIN (-625 3150) $PN EB39
J 0
(-615 3160);
DISPLAY 0.617021 (-615 3160);
PAINT ORANGE (-615 3160);
FORCEPROP 2 LASTPIN (-625 3100) $PN EB41
J 0
(-615 3110);
DISPLAY 0.617021 (-615 3110);
PAINT ORANGE (-615 3110);
FORCEPROP 2 LASTPIN (-625 3050) $PN EB65
J 0
(-615 3060);
DISPLAY 0.617021 (-615 3060);
PAINT ORANGE (-615 3060);
FORCEPROP 2 LASTPIN (-625 3000) $PN EB69
J 0
(-615 3010);
DISPLAY 0.617021 (-615 3010);
PAINT ORANGE (-615 3010);
FORCEPROP 2 LASTPIN (-625 2950) $PN EC10
J 0
(-615 2960);
DISPLAY 0.617021 (-615 2960);
PAINT ORANGE (-615 2960);
FORCEPROP 2 LASTPIN (-625 2900) $PN EC70
J 0
(-615 2910);
DISPLAY 0.617021 (-615 2910);
PAINT ORANGE (-615 2910);
FORCEPROP 2 LASTPIN (-625 2850) $PN EC72
J 0
(-615 2860);
DISPLAY 0.617021 (-615 2860);
PAINT ORANGE (-615 2860);
FORCEPROP 2 LASTPIN (-625 2800) $PN EC74
J 0
(-615 2810);
DISPLAY 0.617021 (-615 2810);
PAINT ORANGE (-615 2810);
FORCEPROP 2 LASTPIN (-625 2750) $PN EC76
J 0
(-615 2760);
DISPLAY 0.617021 (-615 2760);
PAINT ORANGE (-615 2760);
FORCEPROP 2 LASTPIN (-625 2700) $PN ED11
J 0
(-615 2710);
DISPLAY 0.617021 (-615 2710);
PAINT ORANGE (-615 2710);
FORCEPROP 2 LASTPIN (-625 2650) $PN ED15
J 0
(-615 2660);
DISPLAY 0.617021 (-615 2660);
PAINT ORANGE (-615 2660);
FORCEPROP 2 LASTPIN (-625 2600) $PN ED23
J 0
(-615 2610);
DISPLAY 0.617021 (-615 2610);
PAINT ORANGE (-615 2610);
FORCEPROP 2 LASTPIN (-625 2550) $PN ED29
J 0
(-615 2560);
DISPLAY 0.617021 (-615 2560);
PAINT ORANGE (-615 2560);
FORCEPROP 2 LASTPIN (-625 2500) $PN ED35
J 0
(-615 2510);
DISPLAY 0.617021 (-615 2510);
PAINT ORANGE (-615 2510);
FORCEPROP 2 LASTPIN (-625 2450) $PN ED77
J 0
(-615 2460);
DISPLAY 0.617021 (-615 2460);
PAINT ORANGE (-615 2460);
FORCEPROP 2 LASTPIN (-625 2400) $PN EE24
J 0
(-615 2410);
DISPLAY 0.617021 (-615 2410);
PAINT ORANGE (-615 2410);
FORCEPROP 2 LASTPIN (-625 2350) $PN EE28
J 0
(-615 2360);
DISPLAY 0.617021 (-615 2360);
PAINT ORANGE (-615 2360);
FORCEPROP 2 LASTPIN (-625 2300) $PN EE30
J 0
(-615 2310);
DISPLAY 0.617021 (-615 2310);
PAINT ORANGE (-615 2310);
FORCEPROP 2 LASTPIN (-625 2250) $PN EE34
J 0
(-615 2260);
DISPLAY 0.617021 (-615 2260);
PAINT ORANGE (-615 2260);
FORCEPROP 2 LASTPIN (-625 2200) $PN EE36
J 0
(-615 2210);
DISPLAY 0.617021 (-615 2210);
PAINT ORANGE (-615 2210);
FORCEPROP 2 LASTPIN (-625 2150) $PN EE70
J 0
(-615 2160);
DISPLAY 0.617021 (-615 2160);
PAINT ORANGE (-615 2160);
FORCEPROP 2 LASTPIN (-625 2100) $PN EE76
J 0
(-615 2110);
DISPLAY 0.617021 (-615 2110);
PAINT ORANGE (-615 2110);
FORCEPROP 2 LASTPIN (-625 2050) $PN EE78
J 0
(-615 2060);
DISPLAY 0.617021 (-615 2060);
PAINT ORANGE (-615 2060);
FORCEPROP 2 LASTPIN (-625 2000) $PN EF71
J 0
(-615 2010);
DISPLAY 0.617021 (-615 2010);
PAINT ORANGE (-615 2010);
FORCEPROP 2 LASTPIN (-625 1950) $PN EF75
J 0
(-615 1960);
DISPLAY 0.617021 (-615 1960);
PAINT ORANGE (-615 1960);
FORCEPROP 2 LASTPIN (-625 1900) $PN EF79
J 0
(-615 1910);
DISPLAY 0.617021 (-615 1910);
PAINT ORANGE (-615 1910);
FORCEPROP 1 LAST PACK_TYPE BGA1
J 0
(-1775 4850);
PAINT SKYBLUE (-1775 4850);
DISPLAY INVISIBLE (-1775 4850);
FORCEPROP 2 LAST SEC_TYPE BGA1
J 0
(-1775 4850);
DISPLAY 1.021277 (-1775 4850);
PAINT ORANGE (-1775 4850);
DISPLAY INVISIBLE (-1775 4850);
FORCEPROP 2 LAST CDS_LIB chpset_lib
J 0
(-1225 2550);
PAINT ORANGE (-1225 2550);
DISPLAY INVISIBLE (-1225 2550);
FORCEPROP 2 LAST SEC 30
J 0
(-1775 4850);
DISPLAY 0.680851 (-1775 4850);
PAINT MONO (-1775 4850);
DISPLAY INVISIBLE (-1775 4850);
FORCEPROP 2 LAST CDS_LOCATION U2D1
J 0
(-1775 4800);
DISPLAY 0.617021 (-1775 4800);
PAINT AQUA (-1775 4800);
DISPLAY INVISIBLE (-1775 4800);
FORCEPROP 1 LAST PATH I20
J 0
(-1225 4750);
PAINT GREEN (-1225 4750);
DISPLAY INVISIBLE (-1225 4750);
FORCEADD GND..1
(-7475 400);
FORCEPROP 3 LASTPIN (-7475 450) SIG_NAME GND\g
J 0
(-7465 460);
DISPLAY 0.659574 (-7465 460);
PAINT MONO (-7465 460);
DISPLAY INVISIBLE (-7465 460);
FORCEPROP 1 LAST VOLTAGE 0.0V
J 0
(-7520 357);
DISPLAY 0.340426 (-7520 357);
PAINT SKYBLUE (-7520 357);
DISPLAY INVISIBLE (-7520 357);
FORCEPROP 2 LAST CDS_LIB mstr_symbols
J 0
(-7475 400);
PAINT ORANGE (-7475 400);
DISPLAY INVISIBLE (-7475 400);
FORCEPROP 1 LAST SIZE 1B
J 0
(-7400 350);
DISPLAY 1.170213 (-7400 350);
PAINT AQUA (-7400 350);
DISPLAY INVISIBLE (-7400 350);
FORCEPROP 1 LAST BODY_TYPE PLUMBING
J 0
(-7520 357);
DISPLAY 0.340426 (-7520 357);
PAINT GREEN (-7520 357);
DISPLAY INVISIBLE (-7520 357);
FORCEPROP 1 LAST PATH I9
J 0
(-7400 400);
DISPLAY 0.872340 (-7400 400);
PAINT AQUA (-7400 400);
DISPLAY INVISIBLE (-7400 400);
FORCEPROP 1 LAST HDL_POWER GND
J 0
(-7475 550);
DISPLAY 1.170213 (-7475 550);
PAINT GREEN (-7475 550);
DISPLAY INVISIBLE (-7475 550);
FORCEADD PRELIM..10
(-2965 2740);
PAINT GRAY (-2965 2740);
FORCEPROP 2 LAST CDS_LIB mstr_misc
J 0
(-2965 2740);
PAINT ORANGE (-2965 2740);
DISPLAY INVISIBLE (-2965 2740);
FORCEPROP 1 LAST COMMENT_BODY TRUE
J 0
(-2965 2740);
PAINT ORANGE (-2965 2740);
DISPLAY INVISIBLE (-2965 2740);
FORCEADD PRELIM..10
(-4890 2690);
PAINT GRAY (-4890 2690);
FORCEPROP 2 LAST CDS_LIB mstr_misc
J 0
(-4890 2690);
PAINT ORANGE (-4890 2690);
DISPLAY INVISIBLE (-4890 2690);
FORCEPROP 1 LAST COMMENT_BODY TRUE
J 0
(-4890 2690);
PAINT ORANGE (-4890 2690);
DISPLAY INVISIBLE (-4890 2690);
FORCEADD PRELIM..10
(-1215 2840);
PAINT GRAY (-1215 2840);
FORCEPROP 2 LAST CDS_LIB mstr_misc
J 0
(-1215 2840);
PAINT ORANGE (-1215 2840);
DISPLAY INVISIBLE (-1215 2840);
FORCEPROP 1 LAST COMMENT_BODY TRUE
J 0
(-1215 2840);
PAINT ORANGE (-1215 2840);
DISPLAY INVISIBLE (-1215 2840);
FORCEADD DESIGN_NOTE..1
(-6825 250);
FORCEPROP 0 LAST L1 CPU SYMBOLS 1-30 ARE PRELIMINARY AND SUBJECT TO CHANGE
J 0
(-7025 125);
DISPLAY 1.021277 (-7025 125);
PAINT ORANGE (-7025 125);
FORCEPROP 2 LAST CDS_LIB mstr_symbols
J 0
(-6825 250);
PAINT ORANGE (-6825 250);
DISPLAY INVISIBLE (-6825 250);
FORCEPROP 1 LAST COMMENT_BODY TRUE
J 0
(-6800 350);
DISPLAY 0.978723 (-6800 350);
PAINT ORANGE (-6800 350);
DISPLAY INVISIBLE (-6800 350);
FORCEADD INTEL_CORP_BPAGE..1
(0 0);
FORCEPROP 1 LAST CDS_CON_LAST_MODIFIED Tue Dec 01 11:51:39 2015
J 0
(-1425 325);
DISPLAY 1.340426 (-1425 325);
PAINT GREEN (-1425 325);
DISPLAY INVISIBLE (-1425 325);
FORCEPROP 1 LAST CUSTOM_TXT_CDS <CURRENT_DESIGN_SHEET> OF <TOTAL_DESIGN_SHEETS>
J 0
(-500 25);
PAINT GREEN (-500 25);
FORCEPROP 1 LAST CUSTOM_TXT_CDS <CON_LAST_MODIFIED>
J 0
(-1925 350);
PAINT GREEN (-1925 350);
FORCEPROP 2 LAST CUSTOM_TXT_CDS <XR_PAGE_TITLE>
J 0
(-7890 5250);
DISPLAY 0.638298 (-7890 5250);
PAINT PINK (-7890 5250);
DISPLAY INVISIBLE (-7890 5250);
FORCEPROP 1 LAST SCH_ADDRESS3 Santa Clara, CA 95052-8119
J 0
(-3975 25);
DISPLAY 0.617021 (-3975 25);
PAINT GREEN (-3975 25);
FORCEPROP 1 LAST SCH_ADDRESS2 P.O. BOX 58119
J 0
(-3975 75);
DISPLAY 0.617021 (-3975 75);
PAINT GREEN (-3975 75);
FORCEPROP 1 LAST SCH_ADDRESS1 2200 Mission College Blvd.
J 0
(-3975 125);
DISPLAY 0.617021 (-3975 125);
PAINT GREEN (-3975 125);
FORCEPROP 1 LAST SCH_TITLE SKYLAKE - SKT1 - 21 OF 21
J 0
(-7950 50);
DISPLAY 1.212766 (-7950 50);
PAINT GREEN (-7950 50);
FORCEPROP 1 LAST SCH_NUMBER H4694802
J 0
(-1300 150);
DISPLAY 1.212766 (-1300 150);
PAINT YELLOW (-1300 150);
FORCEPROP 1 LAST SCH_DEPT BESD
J 1
(-4450 100);
DISPLAY 1.212766 (-4450 100);
PAINT YELLOW (-4450 100);
FORCEPROP 1 LAST SCH_REV 2.420
J 0
(-250 150);
DISPLAY 0.978723 (-250 150);
PAINT YELLOW (-250 150);
FORCEPROP 2 LAST PAGE_BORDER TRUE
J 0
(-7890 5250);
DISPLAY 0.851064 (-7890 5250);
PAINT PINK (-7890 5250);
DISPLAY INVISIBLE (-7890 5250);
FORCEPROP 2 LAST CDS_LIB mstr_symbols
J 0
(0 0);
PAINT ORANGE (0 0);
DISPLAY INVISIBLE (0 0);
FORCEPROP 1 LAST COMMENT_BODY TRUE
J 0
(12 12);
DISPLAY 0.638298 (12 12);
PAINT GREEN (12 12);
DISPLAY INVISIBLE (12 12);
FORCEPROP 2 LAST CDS_XR_PAGE_TITLE CR-75 : @BASEBOARD_FAB2_LIB.BASEBOARD_FAB2(SCH_1):PAGE75
J 0
(-7890 5250);
DISPLAY 0.638298 (-7890 5250);
PAINT PINK (-7890 5250);
DISPLAY INVISIBLE (-7890 5250);
FORCEADD PRELIM..10
(-6490 2490);
PAINT GRAY (-6490 2490);
FORCEPROP 2 LAST CDS_LIB mstr_misc
J 0
(-6490 2490);
PAINT ORANGE (-6490 2490);
DISPLAY INVISIBLE (-6490 2490);
FORCEPROP 1 LAST COMMENT_BODY TRUE
J 0
(-6490 2490);
PAINT ORANGE (-6490 2490);
DISPLAY INVISIBLE (-6490 2490);
WIRE 16 -1 (-5675 4525)(-5525 4525);
WIRE 16 -1 (-5675 4525)(-5675 4475);
WIRE 16 -1 (-5525 4475)(-5675 4475);
WIRE 16 -1 (-5675 4475)(-5675 4425);
WIRE 16 -1 (-5525 4425)(-5675 4425);
WIRE 16 -1 (-5675 4425)(-5675 4375);
WIRE 16 -1 (-5525 4375)(-5675 4375);
WIRE 16 -1 (-5675 4375)(-5675 4325);
WIRE 16 -1 (-5525 4325)(-5675 4325);
WIRE 16 -1 (-5675 4325)(-5675 4275);
WIRE 16 -1 (-5525 4275)(-5675 4275);
WIRE 16 -1 (-5675 4275)(-5675 4225);
WIRE 16 -1 (-5525 4225)(-5675 4225);
WIRE 16 -1 (-5675 4225)(-5675 4175);
WIRE 16 -1 (-5525 4175)(-5675 4175);
WIRE 16 -1 (-5675 4175)(-5675 4125);
WIRE 16 -1 (-5525 4125)(-5675 4125);
WIRE 16 -1 (-5675 4125)(-5675 4075);
WIRE 16 -1 (-5525 4075)(-5675 4075);
WIRE 16 -1 (-5675 4075)(-5675 4025);
WIRE 16 -1 (-5525 4025)(-5675 4025);
WIRE 16 -1 (-5675 4025)(-5675 3975);
WIRE 16 -1 (-5525 3975)(-5675 3975);
WIRE 16 -1 (-5675 3975)(-5675 3925);
WIRE 16 -1 (-5525 3925)(-5675 3925);
WIRE 16 -1 (-5675 3925)(-5675 3875);
WIRE 16 -1 (-5525 3875)(-5675 3875);
WIRE 16 -1 (-5675 3875)(-5675 3825);
WIRE 16 -1 (-5525 3825)(-5675 3825);
WIRE 16 -1 (-5675 3825)(-5675 3775);
WIRE 16 -1 (-5525 3775)(-5675 3775);
WIRE 16 -1 (-5675 3775)(-5675 3725);
WIRE 16 -1 (-5525 3725)(-5675 3725);
WIRE 16 -1 (-5675 3725)(-5675 3675);
WIRE 16 -1 (-5525 3675)(-5675 3675);
WIRE 16 -1 (-5675 3675)(-5675 3625);
WIRE 16 -1 (-5525 3625)(-5675 3625);
WIRE 16 -1 (-5675 3625)(-5675 3575);
WIRE 16 -1 (-5525 3575)(-5675 3575);
WIRE 16 -1 (-5675 3575)(-5675 3525);
WIRE 16 -1 (-5525 3525)(-5675 3525);
WIRE 16 -1 (-5675 3525)(-5675 3475);
WIRE 16 -1 (-5525 3475)(-5675 3475);
WIRE 16 -1 (-5675 3475)(-5675 3425);
WIRE 16 -1 (-5525 3425)(-5675 3425);
WIRE 16 -1 (-5675 3425)(-5675 3375);
WIRE 16 -1 (-5525 3375)(-5675 3375);
WIRE 16 -1 (-5675 3375)(-5675 3325);
WIRE 16 -1 (-5525 3325)(-5675 3325);
WIRE 16 -1 (-5675 3325)(-5675 3275);
WIRE 16 -1 (-5525 3275)(-5675 3275);
WIRE 16 -1 (-5675 3275)(-5675 3225);
WIRE 16 -1 (-5525 3225)(-5675 3225);
WIRE 16 -1 (-5675 3225)(-5675 3175);
WIRE 16 -1 (-5525 3175)(-5675 3175);
WIRE 16 -1 (-5675 3175)(-5675 3125);
WIRE 16 -1 (-5525 3125)(-5675 3125);
WIRE 16 -1 (-5675 3125)(-5675 3075);
WIRE 16 -1 (-5525 3075)(-5675 3075);
WIRE 16 -1 (-5675 3075)(-5675 3025);
WIRE 16 -1 (-5525 3025)(-5675 3025);
WIRE 16 -1 (-5675 3025)(-5675 2975);
WIRE 16 -1 (-5525 2975)(-5675 2975);
WIRE 16 -1 (-5675 2975)(-5675 2925);
WIRE 16 -1 (-5525 2925)(-5675 2925);
WIRE 16 -1 (-5675 2925)(-5675 2875);
WIRE 16 -1 (-5525 2875)(-5675 2875);
WIRE 16 -1 (-5675 2875)(-5675 2825);
WIRE 16 -1 (-5525 2825)(-5675 2825);
WIRE 16 -1 (-5675 2825)(-5675 2775);
WIRE 16 -1 (-5525 2775)(-5675 2775);
WIRE 16 -1 (-5675 2775)(-5675 2725);
WIRE 16 -1 (-5525 2725)(-5675 2725);
WIRE 16 -1 (-5675 2725)(-5675 2675);
WIRE 16 -1 (-5525 2675)(-5675 2675);
WIRE 16 -1 (-5675 2675)(-5675 2625);
WIRE 16 -1 (-5525 2625)(-5675 2625);
WIRE 16 -1 (-5675 2625)(-5675 2575);
WIRE 16 -1 (-5525 2575)(-5675 2575);
WIRE 16 -1 (-5675 2575)(-5675 2525);
WIRE 16 -1 (-5525 2525)(-5675 2525);
WIRE 16 -1 (-5675 2525)(-5675 2475);
WIRE 16 -1 (-5525 2475)(-5675 2475);
WIRE 16 -1 (-5675 2475)(-5675 2425);
WIRE 16 -1 (-5525 2425)(-5675 2425);
WIRE 16 -1 (-5675 2425)(-5675 2375);
WIRE 16 -1 (-5525 2375)(-5675 2375);
WIRE 16 -1 (-5675 2375)(-5675 2325);
WIRE 16 -1 (-5525 2325)(-5675 2325);
WIRE 16 -1 (-5675 2325)(-5675 2275);
WIRE 16 -1 (-5525 2275)(-5675 2275);
WIRE 16 -1 (-5675 2275)(-5675 2225);
WIRE 16 -1 (-5525 2225)(-5675 2225);
WIRE 16 -1 (-5675 2225)(-5675 2175);
WIRE 16 -1 (-5525 2175)(-5675 2175);
WIRE 16 -1 (-5675 2175)(-5675 2125);
WIRE 16 -1 (-5525 2125)(-5675 2125);
WIRE 16 -1 (-5675 2125)(-5675 2075);
WIRE 16 -1 (-5525 2075)(-5675 2075);
WIRE 16 -1 (-5675 2075)(-5675 2025);
WIRE 16 -1 (-5525 2025)(-5675 2025);
WIRE 16 -1 (-5675 2025)(-5675 1975);
WIRE 16 -1 (-5525 1975)(-5675 1975);
WIRE 16 -1 (-5675 1975)(-5675 1925);
WIRE 16 -1 (-5525 1925)(-5675 1925);
WIRE 16 -1 (-5675 1925)(-5675 1875);
WIRE 16 -1 (-5525 1875)(-5675 1875);
WIRE 16 -1 (-5675 1875)(-5675 1825);
WIRE 16 -1 (-5525 1825)(-5675 1825);
WIRE 16 -1 (-5675 1825)(-5675 1775);
WIRE 16 -1 (-5525 1775)(-5675 1775);
WIRE 16 -1 (-5675 1775)(-5675 1725);
WIRE 16 -1 (-5525 1725)(-5675 1725);
WIRE 16 -1 (-5675 1725)(-5675 1675);
WIRE 16 -1 (-5525 1675)(-5675 1675);
WIRE 16 -1 (-5675 1675)(-5675 1625);
WIRE 16 -1 (-5525 1625)(-5675 1625);
WIRE 16 -1 (-5675 1625)(-5675 1575);
WIRE 16 -1 (-5525 1575)(-5675 1575);
WIRE 16 -1 (-5675 1575)(-5675 1525);
WIRE 16 -1 (-5525 1525)(-5675 1525);
WIRE 16 -1 (-5675 1525)(-5675 1475);
WIRE 16 -1 (-5525 1475)(-5675 1475);
WIRE 16 -1 (-5675 1475)(-5675 1425);
WIRE 16 -1 (-5525 1425)(-5675 1425);
WIRE 16 -1 (-5675 1425)(-5675 1375);
WIRE 16 -1 (-5525 1375)(-5675 1375);
WIRE 16 -1 (-5675 1375)(-5675 1325);
WIRE 16 -1 (-5525 1325)(-5675 1325);
WIRE 16 -1 (-5675 1325)(-5675 1275);
WIRE 16 -1 (-5525 1275)(-5675 1275);
WIRE 16 -1 (-5675 1275)(-5675 1225);
WIRE 16 -1 (-5525 1225)(-5675 1225);
WIRE 16 -1 (-5675 1225)(-5675 1175);
WIRE 16 -1 (-5525 1175)(-5675 1175);
WIRE 16 -1 (-5675 1175)(-5675 1125);
WIRE 16 -1 (-5525 1125)(-5675 1125);
WIRE 16 -1 (-5675 1125)(-5675 1075);
WIRE 16 -1 (-5525 1075)(-5675 1075);
WIRE 16 -1 (-5675 1075)(-5675 1025);
WIRE 16 -1 (-5525 1025)(-5675 1025);
WIRE 16 -1 (-5675 1025)(-5675 975);
WIRE 16 -1 (-5525 975)(-5675 975);
WIRE 16 -1 (-5675 975)(-5675 925);
WIRE 16 -1 (-5525 925)(-5675 925);
WIRE 16 -1 (-5675 925)(-5675 875);
WIRE 16 -1 (-5525 875)(-5675 875);
WIRE 16 -1 (-5675 875)(-5675 825);
WIRE 16 -1 (-5525 825)(-5675 825);
WIRE 16 -1 (-5675 825)(-5675 775);
WIRE 16 -1 (-5525 775)(-5675 775);
WIRE 16 -1 (-5675 775)(-5675 725);
WIRE 16 -1 (-5525 725)(-5675 725);
WIRE 16 -1 (-5675 725)(-5675 675);
WIRE 16 -1 (-5525 675)(-5675 675);
WIRE 16 -1 (-5675 675)(-5675 625);
WIRE 16 -1 (-5525 625)(-5675 625);
WIRE 16 -1 (-5675 625)(-5675 575);
WIRE 16 -1 (-5675 575)(-5525 575);
WIRE 16 -1 (-5675 575)(-5675 450);
WIRE 16 -1 (-3775 4525)(-3650 4525);
WIRE 16 -1 (-3775 4525)(-3775 4475);
WIRE 16 -1 (-3650 4475)(-3775 4475);
WIRE 16 -1 (-3775 4475)(-3775 4425);
WIRE 16 -1 (-3650 4425)(-3775 4425);
WIRE 16 -1 (-3775 4425)(-3775 4375);
WIRE 16 -1 (-3650 4375)(-3775 4375);
WIRE 16 -1 (-3775 4375)(-3775 4325);
WIRE 16 -1 (-3650 4325)(-3775 4325);
WIRE 16 -1 (-3775 4325)(-3775 4275);
WIRE 16 -1 (-3650 4275)(-3775 4275);
WIRE 16 -1 (-3775 4275)(-3775 4225);
WIRE 16 -1 (-3650 4225)(-3775 4225);
WIRE 16 -1 (-3775 4225)(-3775 4175);
WIRE 16 -1 (-3650 4175)(-3775 4175);
WIRE 16 -1 (-3775 4175)(-3775 4125);
WIRE 16 -1 (-3650 4125)(-3775 4125);
WIRE 16 -1 (-3775 4125)(-3775 4075);
WIRE 16 -1 (-3650 4075)(-3775 4075);
WIRE 16 -1 (-3775 4075)(-3775 4025);
WIRE 16 -1 (-3650 4025)(-3775 4025);
WIRE 16 -1 (-3775 4025)(-3775 3975);
WIRE 16 -1 (-3650 3975)(-3775 3975);
WIRE 16 -1 (-3775 3975)(-3775 3925);
WIRE 16 -1 (-3650 3925)(-3775 3925);
WIRE 16 -1 (-3775 3925)(-3775 3875);
WIRE 16 -1 (-3650 3875)(-3775 3875);
WIRE 16 -1 (-3775 3875)(-3775 3825);
WIRE 16 -1 (-3650 3825)(-3775 3825);
WIRE 16 -1 (-3775 3825)(-3775 3775);
WIRE 16 -1 (-3650 3775)(-3775 3775);
WIRE 16 -1 (-3775 3775)(-3775 3725);
WIRE 16 -1 (-3650 3725)(-3775 3725);
WIRE 16 -1 (-3775 3725)(-3775 3675);
WIRE 16 -1 (-3650 3675)(-3775 3675);
WIRE 16 -1 (-3775 3675)(-3775 3625);
WIRE 16 -1 (-3650 3625)(-3775 3625);
WIRE 16 -1 (-3775 3625)(-3775 3575);
WIRE 16 -1 (-3650 3575)(-3775 3575);
WIRE 16 -1 (-3775 3575)(-3775 3525);
WIRE 16 -1 (-3650 3525)(-3775 3525);
WIRE 16 -1 (-3775 3525)(-3775 3475);
WIRE 16 -1 (-3650 3475)(-3775 3475);
WIRE 16 -1 (-3775 3475)(-3775 3425);
WIRE 16 -1 (-3650 3425)(-3775 3425);
WIRE 16 -1 (-3775 3425)(-3775 3375);
WIRE 16 -1 (-3650 3375)(-3775 3375);
WIRE 16 -1 (-3775 3375)(-3775 3325);
WIRE 16 -1 (-3650 3325)(-3775 3325);
WIRE 16 -1 (-3775 3325)(-3775 3275);
WIRE 16 -1 (-3650 3275)(-3775 3275);
WIRE 16 -1 (-3775 3275)(-3775 3225);
WIRE 16 -1 (-3650 3225)(-3775 3225);
WIRE 16 -1 (-3775 3225)(-3775 3175);
WIRE 16 -1 (-3650 3175)(-3775 3175);
WIRE 16 -1 (-3775 3175)(-3775 3125);
WIRE 16 -1 (-3650 3125)(-3775 3125);
WIRE 16 -1 (-3775 3125)(-3775 3075);
WIRE 16 -1 (-3650 3075)(-3775 3075);
WIRE 16 -1 (-3775 3075)(-3775 3025);
WIRE 16 -1 (-3650 3025)(-3775 3025);
WIRE 16 -1 (-3775 3025)(-3775 2975);
WIRE 16 -1 (-3650 2975)(-3775 2975);
WIRE 16 -1 (-3775 2975)(-3775 2925);
WIRE 16 -1 (-3650 2925)(-3775 2925);
WIRE 16 -1 (-3775 2925)(-3775 2875);
WIRE 16 -1 (-3650 2875)(-3775 2875);
WIRE 16 -1 (-3775 2875)(-3775 2825);
WIRE 16 -1 (-3650 2825)(-3775 2825);
WIRE 16 -1 (-3775 2825)(-3775 2775);
WIRE 16 -1 (-3650 2775)(-3775 2775);
WIRE 16 -1 (-3775 2775)(-3775 2725);
WIRE 16 -1 (-3650 2725)(-3775 2725);
WIRE 16 -1 (-3775 2725)(-3775 2675);
WIRE 16 -1 (-3650 2675)(-3775 2675);
WIRE 16 -1 (-3775 2675)(-3775 2625);
WIRE 16 -1 (-3650 2625)(-3775 2625);
WIRE 16 -1 (-3775 2625)(-3775 2575);
WIRE 16 -1 (-3650 2575)(-3775 2575);
WIRE 16 -1 (-3775 2575)(-3775 2525);
WIRE 16 -1 (-3650 2525)(-3775 2525);
WIRE 16 -1 (-3775 2525)(-3775 2475);
WIRE 16 -1 (-3650 2475)(-3775 2475);
WIRE 16 -1 (-3775 2475)(-3775 2425);
WIRE 16 -1 (-3650 2425)(-3775 2425);
WIRE 16 -1 (-3775 2425)(-3775 2375);
WIRE 16 -1 (-3650 2375)(-3775 2375);
WIRE 16 -1 (-3775 2375)(-3775 2325);
WIRE 16 -1 (-3650 2325)(-3775 2325);
WIRE 16 -1 (-3775 2325)(-3775 2275);
WIRE 16 -1 (-3650 2275)(-3775 2275);
WIRE 16 -1 (-3775 2275)(-3775 2225);
WIRE 16 -1 (-3650 2225)(-3775 2225);
WIRE 16 -1 (-3775 2225)(-3775 2175);
WIRE 16 -1 (-3650 2175)(-3775 2175);
WIRE 16 -1 (-3775 2175)(-3775 2125);
WIRE 16 -1 (-3650 2125)(-3775 2125);
WIRE 16 -1 (-3775 2125)(-3775 2075);
WIRE 16 -1 (-3650 2075)(-3775 2075);
WIRE 16 -1 (-3775 2075)(-3775 2025);
WIRE 16 -1 (-3650 2025)(-3775 2025);
WIRE 16 -1 (-3775 2025)(-3775 1975);
WIRE 16 -1 (-3650 1975)(-3775 1975);
WIRE 16 -1 (-3775 1975)(-3775 1925);
WIRE 16 -1 (-3650 1925)(-3775 1925);
WIRE 16 -1 (-3775 1925)(-3775 1875);
WIRE 16 -1 (-3650 1875)(-3775 1875);
WIRE 16 -1 (-3775 1875)(-3775 1825);
WIRE 16 -1 (-3650 1825)(-3775 1825);
WIRE 16 -1 (-3775 1825)(-3775 1775);
WIRE 16 -1 (-3650 1775)(-3775 1775);
WIRE 16 -1 (-3775 1775)(-3775 1725);
WIRE 16 -1 (-3650 1725)(-3775 1725);
WIRE 16 -1 (-3775 1725)(-3775 1675);
WIRE 16 -1 (-3650 1675)(-3775 1675);
WIRE 16 -1 (-3775 1675)(-3775 1625);
WIRE 16 -1 (-3650 1625)(-3775 1625);
WIRE 16 -1 (-3775 1625)(-3775 1575);
WIRE 16 -1 (-3650 1575)(-3775 1575);
WIRE 16 -1 (-3775 1575)(-3775 1525);
WIRE 16 -1 (-3650 1525)(-3775 1525);
WIRE 16 -1 (-3775 1525)(-3775 1475);
WIRE 16 -1 (-3650 1475)(-3775 1475);
WIRE 16 -1 (-3775 1475)(-3775 1425);
WIRE 16 -1 (-3650 1425)(-3775 1425);
WIRE 16 -1 (-3775 1425)(-3775 1375);
WIRE 16 -1 (-3650 1375)(-3775 1375);
WIRE 16 -1 (-3775 1375)(-3775 1325);
WIRE 16 -1 (-3650 1325)(-3775 1325);
WIRE 16 -1 (-3775 1325)(-3775 1275);
WIRE 16 -1 (-3650 1275)(-3775 1275);
WIRE 16 -1 (-3775 1275)(-3775 1225);
WIRE 16 -1 (-3650 1225)(-3775 1225);
WIRE 16 -1 (-3775 1225)(-3775 1175);
WIRE 16 -1 (-3650 1175)(-3775 1175);
WIRE 16 -1 (-3775 1175)(-3775 1125);
WIRE 16 -1 (-3650 1125)(-3775 1125);
WIRE 16 -1 (-3775 1125)(-3775 1075);
WIRE 16 -1 (-3650 1075)(-3775 1075);
WIRE 16 -1 (-3775 1075)(-3775 1025);
WIRE 16 -1 (-3650 1025)(-3775 1025);
WIRE 16 -1 (-3775 1025)(-3775 975);
WIRE 16 -1 (-3650 975)(-3775 975);
WIRE 16 -1 (-3775 975)(-3775 925);
WIRE 16 -1 (-3650 925)(-3775 925);
WIRE 16 -1 (-3775 925)(-3775 875);
WIRE 16 -1 (-3650 875)(-3775 875);
WIRE 16 -1 (-3775 875)(-3775 825);
WIRE 16 -1 (-3650 825)(-3775 825);
WIRE 16 -1 (-3775 825)(-3775 775);
WIRE 16 -1 (-3650 775)(-3775 775);
WIRE 16 -1 (-3775 775)(-3775 725);
WIRE 16 -1 (-3650 725)(-3775 725);
WIRE 16 -1 (-3775 725)(-3775 675);
WIRE 16 -1 (-3650 675)(-3775 675);
WIRE 16 -1 (-3775 675)(-3775 625);
WIRE 16 -1 (-3650 625)(-3775 625);
WIRE 16 -1 (-3775 625)(-3775 575);
WIRE 16 -1 (-3775 575)(-3650 575);
WIRE 16 -1 (-3775 575)(-3775 450);
WIRE 16 -1 (-1975 4550)(-1825 4550);
WIRE 16 -1 (-1975 4550)(-1975 4500);
WIRE 16 -1 (-1825 4500)(-1975 4500);
WIRE 16 -1 (-1975 4500)(-1975 4450);
WIRE 16 -1 (-1825 4450)(-1975 4450);
WIRE 16 -1 (-1975 4450)(-1975 4400);
WIRE 16 -1 (-1825 4400)(-1975 4400);
WIRE 16 -1 (-1975 4400)(-1975 4350);
WIRE 16 -1 (-1825 4350)(-1975 4350);
WIRE 16 -1 (-1975 4350)(-1975 4300);
WIRE 16 -1 (-1825 4300)(-1975 4300);
WIRE 16 -1 (-1975 4300)(-1975 4250);
WIRE 16 -1 (-1825 4250)(-1975 4250);
WIRE 16 -1 (-1975 4250)(-1975 4200);
WIRE 16 -1 (-1825 4200)(-1975 4200);
WIRE 16 -1 (-1975 4150)(-1975 4200);
WIRE 16 -1 (-1825 4150)(-1975 4150);
WIRE 16 -1 (-1975 4100)(-1975 4150);
WIRE 16 -1 (-1825 4100)(-1975 4100);
WIRE 16 -1 (-1975 4050)(-1975 4100);
WIRE 16 -1 (-1825 4050)(-1975 4050);
WIRE 16 -1 (-1975 4000)(-1975 4050);
WIRE 16 -1 (-1825 4000)(-1975 4000);
WIRE 16 -1 (-1975 3950)(-1975 4000);
WIRE 16 -1 (-1825 3950)(-1975 3950);
WIRE 16 -1 (-1975 3900)(-1975 3950);
WIRE 16 -1 (-1825 3900)(-1975 3900);
WIRE 16 -1 (-1975 3850)(-1975 3900);
WIRE 16 -1 (-1825 3850)(-1975 3850);
WIRE 16 -1 (-1975 3800)(-1975 3850);
WIRE 16 -1 (-1825 3800)(-1975 3800);
WIRE 16 -1 (-1975 3750)(-1975 3800);
WIRE 16 -1 (-1825 3750)(-1975 3750);
WIRE 16 -1 (-1975 3700)(-1975 3750);
WIRE 16 -1 (-1825 3700)(-1975 3700);
WIRE 16 -1 (-1975 3650)(-1975 3700);
WIRE 16 -1 (-1825 3650)(-1975 3650);
WIRE 16 -1 (-1975 3600)(-1975 3650);
WIRE 16 -1 (-1825 3600)(-1975 3600);
WIRE 16 -1 (-1975 3550)(-1975 3600);
WIRE 16 -1 (-1825 3550)(-1975 3550);
WIRE 16 -1 (-1975 3500)(-1975 3550);
WIRE 16 -1 (-1825 3500)(-1975 3500);
WIRE 16 -1 (-1975 3450)(-1975 3500);
WIRE 16 -1 (-1825 3450)(-1975 3450);
WIRE 16 -1 (-1975 3400)(-1975 3450);
WIRE 16 -1 (-1825 3400)(-1975 3400);
WIRE 16 -1 (-1975 3350)(-1975 3400);
WIRE 16 -1 (-1825 3350)(-1975 3350);
WIRE 16 -1 (-1975 3300)(-1975 3350);
WIRE 16 -1 (-1825 3300)(-1975 3300);
WIRE 16 -1 (-1975 3250)(-1975 3300);
WIRE 16 -1 (-1825 3250)(-1975 3250);
WIRE 16 -1 (-1975 3200)(-1975 3250);
WIRE 16 -1 (-1825 3200)(-1975 3200);
WIRE 16 -1 (-1975 3150)(-1975 3200);
WIRE 16 -1 (-1825 3150)(-1975 3150);
WIRE 16 -1 (-1975 3100)(-1975 3150);
WIRE 16 -1 (-1825 3100)(-1975 3100);
WIRE 16 -1 (-1975 3050)(-1975 3100);
WIRE 16 -1 (-1825 3050)(-1975 3050);
WIRE 16 -1 (-1975 3000)(-1975 3050);
WIRE 16 -1 (-1825 3000)(-1975 3000);
WIRE 16 -1 (-1975 2950)(-1975 3000);
WIRE 16 -1 (-1825 2950)(-1975 2950);
WIRE 16 -1 (-1975 2900)(-1975 2950);
WIRE 16 -1 (-1825 2900)(-1975 2900);
WIRE 16 -1 (-1975 2850)(-1975 2900);
WIRE 16 -1 (-1825 2850)(-1975 2850);
WIRE 16 -1 (-1975 2800)(-1975 2850);
WIRE 16 -1 (-1825 2800)(-1975 2800);
WIRE 16 -1 (-1975 2750)(-1975 2800);
WIRE 16 -1 (-1825 2750)(-1975 2750);
WIRE 16 -1 (-1975 2700)(-1975 2750);
WIRE 16 -1 (-1825 2700)(-1975 2700);
WIRE 16 -1 (-1975 2650)(-1975 2700);
WIRE 16 -1 (-1825 2650)(-1975 2650);
WIRE 16 -1 (-1975 2600)(-1975 2650);
WIRE 16 -1 (-1825 2600)(-1975 2600);
WIRE 16 -1 (-1975 2550)(-1975 2600);
WIRE 16 -1 (-1825 2550)(-1975 2550);
WIRE 16 -1 (-1975 2500)(-1975 2550);
WIRE 16 -1 (-1825 2500)(-1975 2500);
WIRE 16 -1 (-1975 2450)(-1975 2500);
WIRE 16 -1 (-1825 2450)(-1975 2450);
WIRE 16 -1 (-1975 2400)(-1975 2450);
WIRE 16 -1 (-1825 2400)(-1975 2400);
WIRE 16 -1 (-1975 2350)(-1975 2400);
WIRE 16 -1 (-1825 2350)(-1975 2350);
WIRE 16 -1 (-1975 2300)(-1975 2350);
WIRE 16 -1 (-1825 2300)(-1975 2300);
WIRE 16 -1 (-1975 2250)(-1975 2300);
WIRE 16 -1 (-1825 2250)(-1975 2250);
WIRE 16 -1 (-1975 2200)(-1975 2250);
WIRE 16 -1 (-1825 2200)(-1975 2200);
WIRE 16 -1 (-1975 2150)(-1975 2200);
WIRE 16 -1 (-1825 2150)(-1975 2150);
WIRE 16 -1 (-1975 2100)(-1975 2150);
WIRE 16 -1 (-1825 2100)(-1975 2100);
WIRE 16 -1 (-1975 2050)(-1975 2100);
WIRE 16 -1 (-1825 2050)(-1975 2050);
WIRE 16 -1 (-1975 2000)(-1975 2050);
WIRE 16 -1 (-1825 2000)(-1975 2000);
WIRE 16 -1 (-1975 1950)(-1975 2000);
WIRE 16 -1 (-1825 1950)(-1975 1950);
WIRE 16 -1 (-1975 1900)(-1975 1950);
WIRE 16 -1 (-1825 1900)(-1975 1900);
WIRE 16 -1 (-1975 1850)(-1975 1900);
WIRE 16 -1 (-1825 1850)(-1975 1850);
WIRE 16 -1 (-1975 1800)(-1975 1850);
WIRE 16 -1 (-1825 1800)(-1975 1800);
WIRE 16 -1 (-1975 1750)(-1975 1800);
WIRE 16 -1 (-1825 1750)(-1975 1750);
WIRE 16 -1 (-1975 1700)(-1975 1750);
WIRE 16 -1 (-1825 1700)(-1975 1700);
WIRE 16 -1 (-1975 1650)(-1975 1700);
WIRE 16 -1 (-1825 1650)(-1975 1650);
WIRE 16 -1 (-1975 1600)(-1975 1650);
WIRE 16 -1 (-1825 1600)(-1975 1600);
WIRE 16 -1 (-1975 1550)(-1975 1600);
WIRE 16 -1 (-1825 1550)(-1975 1550);
WIRE 16 -1 (-1975 1500)(-1975 1550);
WIRE 16 -1 (-1825 1500)(-1975 1500);
WIRE 16 -1 (-1975 1450)(-1975 1500);
WIRE 16 -1 (-1825 1450)(-1975 1450);
WIRE 16 -1 (-1975 1400)(-1975 1450);
WIRE 16 -1 (-1825 1400)(-1975 1400);
WIRE 16 -1 (-1975 1350)(-1975 1400);
WIRE 16 -1 (-1825 1350)(-1975 1350);
WIRE 16 -1 (-1975 1300)(-1975 1350);
WIRE 16 -1 (-1825 1300)(-1975 1300);
WIRE 16 -1 (-1975 1300)(-1975 1250);
WIRE 16 -1 (-1825 1250)(-1975 1250);
WIRE 16 -1 (-1975 1250)(-1975 1200);
WIRE 16 -1 (-1825 1200)(-1975 1200);
WIRE 16 -1 (-1975 1200)(-1975 1150);
WIRE 16 -1 (-1825 1150)(-1975 1150);
WIRE 16 -1 (-1975 1150)(-1975 1100);
WIRE 16 -1 (-1825 1100)(-1975 1100);
WIRE 16 -1 (-1975 1100)(-1975 1050);
WIRE 16 -1 (-1825 1050)(-1975 1050);
WIRE 16 -1 (-1975 1050)(-1975 1000);
WIRE 16 -1 (-1825 1000)(-1975 1000);
WIRE 16 -1 (-1975 1000)(-1975 950);
WIRE 16 -1 (-1825 950)(-1975 950);
WIRE 16 -1 (-1975 950)(-1975 900);
WIRE 16 -1 (-1825 900)(-1975 900);
WIRE 16 -1 (-1975 900)(-1975 850);
WIRE 16 -1 (-1825 850)(-1975 850);
WIRE 16 -1 (-1975 850)(-1975 800);
WIRE 16 -1 (-1825 800)(-1975 800);
WIRE 16 -1 (-1975 800)(-1975 750);
WIRE 16 -1 (-1825 750)(-1975 750);
WIRE 16 -1 (-1975 750)(-1975 700);
WIRE 16 -1 (-1825 700)(-1975 700);
WIRE 16 -1 (-1975 700)(-1975 650);
WIRE 16 -1 (-1825 650)(-1975 650);
WIRE 16 -1 (-1975 650)(-1975 600);
WIRE 16 -1 (-1825 600)(-1975 600);
WIRE 16 -1 (-1975 600)(-1975 450);
WIRE 16 -1 (-2450 4525)(-2275 4525);
WIRE 16 -1 (-2275 4525)(-2275 4475);
WIRE 16 -1 (-2450 4475)(-2275 4475);
WIRE 16 -1 (-2275 4475)(-2275 4425);
WIRE 16 -1 (-2450 4425)(-2275 4425);
WIRE 16 -1 (-2275 4425)(-2275 4375);
WIRE 16 -1 (-2450 4375)(-2275 4375);
WIRE 16 -1 (-2275 4375)(-2275 4325);
WIRE 16 -1 (-2450 4325)(-2275 4325);
WIRE 16 -1 (-2275 4325)(-2275 4275);
WIRE 16 -1 (-2450 4275)(-2275 4275);
WIRE 16 -1 (-2275 4275)(-2275 4225);
WIRE 16 -1 (-2450 4225)(-2275 4225);
WIRE 16 -1 (-2275 4225)(-2275 4175);
WIRE 16 -1 (-2450 4175)(-2275 4175);
WIRE 16 -1 (-2275 4175)(-2275 4125);
WIRE 16 -1 (-2450 4125)(-2275 4125);
WIRE 16 -1 (-2275 4125)(-2275 4075);
WIRE 16 -1 (-2450 4075)(-2275 4075);
WIRE 16 -1 (-2275 4075)(-2275 4025);
WIRE 16 -1 (-2450 4025)(-2275 4025);
WIRE 16 -1 (-2275 4025)(-2275 3975);
WIRE 16 -1 (-2450 3975)(-2275 3975);
WIRE 16 -1 (-2275 3975)(-2275 3925);
WIRE 16 -1 (-2450 3925)(-2275 3925);
WIRE 16 -1 (-2275 3925)(-2275 3875);
WIRE 16 -1 (-2450 3875)(-2275 3875);
WIRE 16 -1 (-2275 3875)(-2275 3825);
WIRE 16 -1 (-2450 3825)(-2275 3825);
WIRE 16 -1 (-2275 3825)(-2275 3775);
WIRE 16 -1 (-2450 3775)(-2275 3775);
WIRE 16 -1 (-2275 3775)(-2275 3725);
WIRE 16 -1 (-2450 3725)(-2275 3725);
WIRE 16 -1 (-2275 3725)(-2275 3675);
WIRE 16 -1 (-2450 3675)(-2275 3675);
WIRE 16 -1 (-2275 3675)(-2275 3625);
WIRE 16 -1 (-2450 3625)(-2275 3625);
WIRE 16 -1 (-2275 3625)(-2275 3575);
WIRE 16 -1 (-2450 3575)(-2275 3575);
WIRE 16 -1 (-2275 3575)(-2275 3525);
WIRE 16 -1 (-2450 3525)(-2275 3525);
WIRE 16 -1 (-2275 3525)(-2275 3475);
WIRE 16 -1 (-2450 3475)(-2275 3475);
WIRE 16 -1 (-2275 3475)(-2275 3425);
WIRE 16 -1 (-2450 3425)(-2275 3425);
WIRE 16 -1 (-2275 3425)(-2275 3375);
WIRE 16 -1 (-2450 3375)(-2275 3375);
WIRE 16 -1 (-2275 3375)(-2275 3325);
WIRE 16 -1 (-2450 3325)(-2275 3325);
WIRE 16 -1 (-2275 3325)(-2275 3275);
WIRE 16 -1 (-2450 3275)(-2275 3275);
WIRE 16 -1 (-2275 3275)(-2275 3225);
WIRE 16 -1 (-2450 3225)(-2275 3225);
WIRE 16 -1 (-2275 3225)(-2275 3175);
WIRE 16 -1 (-2450 3175)(-2275 3175);
WIRE 16 -1 (-2275 3175)(-2275 3125);
WIRE 16 -1 (-2450 3125)(-2275 3125);
WIRE 16 -1 (-2275 3125)(-2275 3075);
WIRE 16 -1 (-2450 3075)(-2275 3075);
WIRE 16 -1 (-2275 3075)(-2275 3025);
WIRE 16 -1 (-2450 3025)(-2275 3025);
WIRE 16 -1 (-2275 3025)(-2275 2975);
WIRE 16 -1 (-2450 2975)(-2275 2975);
WIRE 16 -1 (-2275 2975)(-2275 2925);
WIRE 16 -1 (-2450 2925)(-2275 2925);
WIRE 16 -1 (-2275 2925)(-2275 2875);
WIRE 16 -1 (-2450 2875)(-2275 2875);
WIRE 16 -1 (-2275 2875)(-2275 2825);
WIRE 16 -1 (-2450 2825)(-2275 2825);
WIRE 16 -1 (-2275 2825)(-2275 2775);
WIRE 16 -1 (-2450 2775)(-2275 2775);
WIRE 16 -1 (-2275 2775)(-2275 2725);
WIRE 16 -1 (-2450 2725)(-2275 2725);
WIRE 16 -1 (-2275 2725)(-2275 2675);
WIRE 16 -1 (-2450 2675)(-2275 2675);
WIRE 16 -1 (-2275 2675)(-2275 2625);
WIRE 16 -1 (-2450 2625)(-2275 2625);
WIRE 16 -1 (-2275 2625)(-2275 2575);
WIRE 16 -1 (-2450 2575)(-2275 2575);
WIRE 16 -1 (-2275 2575)(-2275 2525);
WIRE 16 -1 (-2450 2525)(-2275 2525);
WIRE 16 -1 (-2275 2525)(-2275 2475);
WIRE 16 -1 (-2450 2475)(-2275 2475);
WIRE 16 -1 (-2275 2475)(-2275 2425);
WIRE 16 -1 (-2450 2425)(-2275 2425);
WIRE 16 -1 (-2275 2425)(-2275 2375);
WIRE 16 -1 (-2450 2375)(-2275 2375);
WIRE 16 -1 (-2275 2375)(-2275 2325);
WIRE 16 -1 (-2450 2325)(-2275 2325);
WIRE 16 -1 (-2275 2325)(-2275 2275);
WIRE 16 -1 (-2450 2275)(-2275 2275);
WIRE 16 -1 (-2275 2275)(-2275 2225);
WIRE 16 -1 (-2450 2225)(-2275 2225);
WIRE 16 -1 (-2275 2225)(-2275 2175);
WIRE 16 -1 (-2450 2175)(-2275 2175);
WIRE 16 -1 (-2275 2175)(-2275 2125);
WIRE 16 -1 (-2450 2125)(-2275 2125);
WIRE 16 -1 (-2275 2125)(-2275 2075);
WIRE 16 -1 (-2450 2075)(-2275 2075);
WIRE 16 -1 (-2275 2075)(-2275 2025);
WIRE 16 -1 (-2450 2025)(-2275 2025);
WIRE 16 -1 (-2275 2025)(-2275 1975);
WIRE 16 -1 (-2450 1975)(-2275 1975);
WIRE 16 -1 (-2275 1975)(-2275 1925);
WIRE 16 -1 (-2450 1925)(-2275 1925);
WIRE 16 -1 (-2275 1925)(-2275 1875);
WIRE 16 -1 (-2450 1875)(-2275 1875);
WIRE 16 -1 (-2275 1875)(-2275 1825);
WIRE 16 -1 (-2450 1825)(-2275 1825);
WIRE 16 -1 (-2275 1825)(-2275 1775);
WIRE 16 -1 (-2450 1775)(-2275 1775);
WIRE 16 -1 (-2275 1775)(-2275 1725);
WIRE 16 -1 (-2450 1725)(-2275 1725);
WIRE 16 -1 (-2275 1725)(-2275 1675);
WIRE 16 -1 (-2450 1675)(-2275 1675);
WIRE 16 -1 (-2275 1675)(-2275 1625);
WIRE 16 -1 (-2450 1625)(-2275 1625);
WIRE 16 -1 (-2275 1625)(-2275 1575);
WIRE 16 -1 (-2450 1575)(-2275 1575);
WIRE 16 -1 (-2275 1575)(-2275 1525);
WIRE 16 -1 (-2450 1525)(-2275 1525);
WIRE 16 -1 (-2275 1525)(-2275 1475);
WIRE 16 -1 (-2450 1475)(-2275 1475);
WIRE 16 -1 (-2275 1475)(-2275 1425);
WIRE 16 -1 (-2450 1425)(-2275 1425);
WIRE 16 -1 (-2275 1425)(-2275 1375);
WIRE 16 -1 (-2450 1375)(-2275 1375);
WIRE 16 -1 (-2275 1375)(-2275 1325);
WIRE 16 -1 (-2450 1325)(-2275 1325);
WIRE 16 -1 (-2275 1325)(-2275 1275);
WIRE 16 -1 (-2450 1275)(-2275 1275);
WIRE 16 -1 (-2275 1275)(-2275 1225);
WIRE 16 -1 (-2450 1225)(-2275 1225);
WIRE 16 -1 (-2275 1225)(-2275 1175);
WIRE 16 -1 (-2450 1175)(-2275 1175);
WIRE 16 -1 (-2275 1175)(-2275 1125);
WIRE 16 -1 (-2450 1125)(-2275 1125);
WIRE 16 -1 (-2275 1125)(-2275 1075);
WIRE 16 -1 (-2450 1075)(-2275 1075);
WIRE 16 -1 (-2275 1075)(-2275 1025);
WIRE 16 -1 (-2450 1025)(-2275 1025);
WIRE 16 -1 (-2275 1025)(-2275 975);
WIRE 16 -1 (-2450 975)(-2275 975);
WIRE 16 -1 (-2275 975)(-2275 925);
WIRE 16 -1 (-2450 925)(-2275 925);
WIRE 16 -1 (-2275 925)(-2275 875);
WIRE 16 -1 (-2450 875)(-2275 875);
WIRE 16 -1 (-2275 875)(-2275 825);
WIRE 16 -1 (-2450 825)(-2275 825);
WIRE 16 -1 (-2275 825)(-2275 775);
WIRE 16 -1 (-2450 775)(-2275 775);
WIRE 16 -1 (-2275 775)(-2275 725);
WIRE 16 -1 (-2450 725)(-2275 725);
WIRE 16 -1 (-2275 725)(-2275 675);
WIRE 16 -1 (-2450 675)(-2275 675);
WIRE 16 -1 (-2275 675)(-2275 625);
WIRE 16 -1 (-2450 625)(-2275 625);
WIRE 16 -1 (-2275 625)(-2275 575);
WIRE 16 -1 (-2450 575)(-2275 575);
WIRE 16 -1 (-2275 575)(-2275 450);
WIRE 16 -1 (-4325 4525)(-4150 4525);
WIRE 16 -1 (-4150 4525)(-4150 4475);
WIRE 16 -1 (-4325 4475)(-4150 4475);
WIRE 16 -1 (-4150 4475)(-4150 4425);
WIRE 16 -1 (-4325 4425)(-4150 4425);
WIRE 16 -1 (-4150 4425)(-4150 4375);
WIRE 16 -1 (-4325 4375)(-4150 4375);
WIRE 16 -1 (-4150 4375)(-4150 4325);
WIRE 16 -1 (-4325 4325)(-4150 4325);
WIRE 16 -1 (-4150 4325)(-4150 4275);
WIRE 16 -1 (-4325 4275)(-4150 4275);
WIRE 16 -1 (-4150 4275)(-4150 4225);
WIRE 16 -1 (-4325 4225)(-4150 4225);
WIRE 16 -1 (-4150 4225)(-4150 4175);
WIRE 16 -1 (-4325 4175)(-4150 4175);
WIRE 16 -1 (-4150 4175)(-4150 4125);
WIRE 16 -1 (-4325 4125)(-4150 4125);
WIRE 16 -1 (-4150 4125)(-4150 4075);
WIRE 16 -1 (-4325 4075)(-4150 4075);
WIRE 16 -1 (-4150 4075)(-4150 4025);
WIRE 16 -1 (-4325 4025)(-4150 4025);
WIRE 16 -1 (-4150 4025)(-4150 3975);
WIRE 16 -1 (-4325 3975)(-4150 3975);
WIRE 16 -1 (-4150 3975)(-4150 3925);
WIRE 16 -1 (-4325 3925)(-4150 3925);
WIRE 16 -1 (-4150 3925)(-4150 3875);
WIRE 16 -1 (-4325 3875)(-4150 3875);
WIRE 16 -1 (-4150 3875)(-4150 3825);
WIRE 16 -1 (-4325 3825)(-4150 3825);
WIRE 16 -1 (-4150 3825)(-4150 3775);
WIRE 16 -1 (-4325 3775)(-4150 3775);
WIRE 16 -1 (-4150 3775)(-4150 3725);
WIRE 16 -1 (-4325 3725)(-4150 3725);
WIRE 16 -1 (-4150 3725)(-4150 3675);
WIRE 16 -1 (-4325 3675)(-4150 3675);
WIRE 16 -1 (-4150 3675)(-4150 3625);
WIRE 16 -1 (-4325 3625)(-4150 3625);
WIRE 16 -1 (-4150 3625)(-4150 3575);
WIRE 16 -1 (-4325 3575)(-4150 3575);
WIRE 16 -1 (-4150 3575)(-4150 3525);
WIRE 16 -1 (-4325 3525)(-4150 3525);
WIRE 16 -1 (-4150 3525)(-4150 3475);
WIRE 16 -1 (-4325 3475)(-4150 3475);
WIRE 16 -1 (-4150 3475)(-4150 3425);
WIRE 16 -1 (-4325 3425)(-4150 3425);
WIRE 16 -1 (-4150 3425)(-4150 3375);
WIRE 16 -1 (-4325 3375)(-4150 3375);
WIRE 16 -1 (-4150 3375)(-4150 3325);
WIRE 16 -1 (-4325 3325)(-4150 3325);
WIRE 16 -1 (-4150 3325)(-4150 3275);
WIRE 16 -1 (-4325 3275)(-4150 3275);
WIRE 16 -1 (-4150 3275)(-4150 3225);
WIRE 16 -1 (-4325 3225)(-4150 3225);
WIRE 16 -1 (-4150 3225)(-4150 3175);
WIRE 16 -1 (-4325 3175)(-4150 3175);
WIRE 16 -1 (-4150 3175)(-4150 3125);
WIRE 16 -1 (-4325 3125)(-4150 3125);
WIRE 16 -1 (-4150 3125)(-4150 3075);
WIRE 16 -1 (-4325 3075)(-4150 3075);
WIRE 16 -1 (-4150 3075)(-4150 3025);
WIRE 16 -1 (-4325 3025)(-4150 3025);
WIRE 16 -1 (-4150 3025)(-4150 2975);
WIRE 16 -1 (-4325 2975)(-4150 2975);
WIRE 16 -1 (-4150 2975)(-4150 2925);
WIRE 16 -1 (-4325 2925)(-4150 2925);
WIRE 16 -1 (-4150 2925)(-4150 2875);
WIRE 16 -1 (-4325 2875)(-4150 2875);
WIRE 16 -1 (-4150 2875)(-4150 2825);
WIRE 16 -1 (-4325 2825)(-4150 2825);
WIRE 16 -1 (-4150 2825)(-4150 2775);
WIRE 16 -1 (-4325 2775)(-4150 2775);
WIRE 16 -1 (-4150 2775)(-4150 2725);
WIRE 16 -1 (-4325 2725)(-4150 2725);
WIRE 16 -1 (-4150 2725)(-4150 2675);
WIRE 16 -1 (-4325 2675)(-4150 2675);
WIRE 16 -1 (-4150 2675)(-4150 2625);
WIRE 16 -1 (-4325 2625)(-4150 2625);
WIRE 16 -1 (-4150 2625)(-4150 2575);
WIRE 16 -1 (-4325 2575)(-4150 2575);
WIRE 16 -1 (-4150 2575)(-4150 2525);
WIRE 16 -1 (-4325 2525)(-4150 2525);
WIRE 16 -1 (-4150 2525)(-4150 2475);
WIRE 16 -1 (-4325 2475)(-4150 2475);
WIRE 16 -1 (-4150 2475)(-4150 2425);
WIRE 16 -1 (-4325 2425)(-4150 2425);
WIRE 16 -1 (-4150 2425)(-4150 2375);
WIRE 16 -1 (-4325 2375)(-4150 2375);
WIRE 16 -1 (-4150 2375)(-4150 2325);
WIRE 16 -1 (-4325 2325)(-4150 2325);
WIRE 16 -1 (-4150 2325)(-4150 2275);
WIRE 16 -1 (-4325 2275)(-4150 2275);
WIRE 16 -1 (-4150 2275)(-4150 2225);
WIRE 16 -1 (-4325 2225)(-4150 2225);
WIRE 16 -1 (-4150 2225)(-4150 2175);
WIRE 16 -1 (-4325 2175)(-4150 2175);
WIRE 16 -1 (-4150 2175)(-4150 2125);
WIRE 16 -1 (-4325 2125)(-4150 2125);
WIRE 16 -1 (-4150 2125)(-4150 2075);
WIRE 16 -1 (-4325 2075)(-4150 2075);
WIRE 16 -1 (-4150 2075)(-4150 2025);
WIRE 16 -1 (-4325 2025)(-4150 2025);
WIRE 16 -1 (-4150 2025)(-4150 1975);
WIRE 16 -1 (-4325 1975)(-4150 1975);
WIRE 16 -1 (-4150 1975)(-4150 1925);
WIRE 16 -1 (-4325 1925)(-4150 1925);
WIRE 16 -1 (-4150 1925)(-4150 1875);
WIRE 16 -1 (-4325 1875)(-4150 1875);
WIRE 16 -1 (-4150 1875)(-4150 1825);
WIRE 16 -1 (-4325 1825)(-4150 1825);
WIRE 16 -1 (-4150 1825)(-4150 1775);
WIRE 16 -1 (-4325 1775)(-4150 1775);
WIRE 16 -1 (-4150 1775)(-4150 1725);
WIRE 16 -1 (-4325 1725)(-4150 1725);
WIRE 16 -1 (-4150 1725)(-4150 1675);
WIRE 16 -1 (-4325 1675)(-4150 1675);
WIRE 16 -1 (-4150 1675)(-4150 1625);
WIRE 16 -1 (-4325 1625)(-4150 1625);
WIRE 16 -1 (-4150 1625)(-4150 1575);
WIRE 16 -1 (-4325 1575)(-4150 1575);
WIRE 16 -1 (-4150 1575)(-4150 1525);
WIRE 16 -1 (-4325 1525)(-4150 1525);
WIRE 16 -1 (-4150 1525)(-4150 1475);
WIRE 16 -1 (-4325 1475)(-4150 1475);
WIRE 16 -1 (-4150 1475)(-4150 1425);
WIRE 16 -1 (-4325 1425)(-4150 1425);
WIRE 16 -1 (-4150 1425)(-4150 1375);
WIRE 16 -1 (-4325 1375)(-4150 1375);
WIRE 16 -1 (-4150 1375)(-4150 1325);
WIRE 16 -1 (-4325 1325)(-4150 1325);
WIRE 16 -1 (-4150 1325)(-4150 1275);
WIRE 16 -1 (-4325 1275)(-4150 1275);
WIRE 16 -1 (-4150 1275)(-4150 1225);
WIRE 16 -1 (-4325 1225)(-4150 1225);
WIRE 16 -1 (-4150 1225)(-4150 1175);
WIRE 16 -1 (-4325 1175)(-4150 1175);
WIRE 16 -1 (-4150 1175)(-4150 1125);
WIRE 16 -1 (-4325 1125)(-4150 1125);
WIRE 16 -1 (-4150 1125)(-4150 1075);
WIRE 16 -1 (-4325 1075)(-4150 1075);
WIRE 16 -1 (-4150 1075)(-4150 1025);
WIRE 16 -1 (-4325 1025)(-4150 1025);
WIRE 16 -1 (-4150 1025)(-4150 975);
WIRE 16 -1 (-4325 975)(-4150 975);
WIRE 16 -1 (-4150 975)(-4150 925);
WIRE 16 -1 (-4325 925)(-4150 925);
WIRE 16 -1 (-4150 925)(-4150 875);
WIRE 16 -1 (-4325 875)(-4150 875);
WIRE 16 -1 (-4150 875)(-4150 825);
WIRE 16 -1 (-4325 825)(-4150 825);
WIRE 16 -1 (-4150 825)(-4150 775);
WIRE 16 -1 (-4325 775)(-4150 775);
WIRE 16 -1 (-4150 775)(-4150 725);
WIRE 16 -1 (-4325 725)(-4150 725);
WIRE 16 -1 (-4150 725)(-4150 675);
WIRE 16 -1 (-4325 675)(-4150 675);
WIRE 16 -1 (-4150 675)(-4150 625);
WIRE 16 -1 (-4325 625)(-4150 625);
WIRE 16 -1 (-4150 625)(-4150 575);
WIRE 16 -1 (-4325 575)(-4150 575);
WIRE 16 -1 (-4150 575)(-4150 450);
WIRE 16 -1 (-6125 4525)(-5950 4525);
WIRE 16 -1 (-5950 4525)(-5950 4475);
WIRE 16 -1 (-6125 4475)(-5950 4475);
WIRE 16 -1 (-5950 4475)(-5950 4425);
WIRE 16 -1 (-6125 4425)(-5950 4425);
WIRE 16 -1 (-5950 4425)(-5950 4375);
WIRE 16 -1 (-6125 4375)(-5950 4375);
WIRE 16 -1 (-5950 4375)(-5950 4325);
WIRE 16 -1 (-6125 4325)(-5950 4325);
WIRE 16 -1 (-5950 4325)(-5950 4275);
WIRE 16 -1 (-6125 4275)(-5950 4275);
WIRE 16 -1 (-5950 4275)(-5950 4225);
WIRE 16 -1 (-6125 4225)(-5950 4225);
WIRE 16 -1 (-5950 4225)(-5950 4175);
WIRE 16 -1 (-6125 4175)(-5950 4175);
WIRE 16 -1 (-5950 4175)(-5950 4125);
WIRE 16 -1 (-6125 4125)(-5950 4125);
WIRE 16 -1 (-5950 4125)(-5950 4075);
WIRE 16 -1 (-6125 4075)(-5950 4075);
WIRE 16 -1 (-5950 4075)(-5950 4025);
WIRE 16 -1 (-6125 4025)(-5950 4025);
WIRE 16 -1 (-5950 4025)(-5950 3975);
WIRE 16 -1 (-6125 3975)(-5950 3975);
WIRE 16 -1 (-5950 3975)(-5950 3925);
WIRE 16 -1 (-6125 3925)(-5950 3925);
WIRE 16 -1 (-5950 3925)(-5950 3875);
WIRE 16 -1 (-6125 3875)(-5950 3875);
WIRE 16 -1 (-5950 3875)(-5950 3825);
WIRE 16 -1 (-6125 3825)(-5950 3825);
WIRE 16 -1 (-5950 3825)(-5950 3775);
WIRE 16 -1 (-6125 3775)(-5950 3775);
WIRE 16 -1 (-5950 3775)(-5950 3725);
WIRE 16 -1 (-6125 3725)(-5950 3725);
WIRE 16 -1 (-5950 3725)(-5950 3675);
WIRE 16 -1 (-6125 3675)(-5950 3675);
WIRE 16 -1 (-5950 3675)(-5950 3625);
WIRE 16 -1 (-6125 3625)(-5950 3625);
WIRE 16 -1 (-5950 3625)(-5950 3575);
WIRE 16 -1 (-6125 3575)(-5950 3575);
WIRE 16 -1 (-5950 3575)(-5950 3525);
WIRE 16 -1 (-6125 3525)(-5950 3525);
WIRE 16 -1 (-5950 3525)(-5950 3475);
WIRE 16 -1 (-6125 3475)(-5950 3475);
WIRE 16 -1 (-5950 3475)(-5950 3425);
WIRE 16 -1 (-6125 3425)(-5950 3425);
WIRE 16 -1 (-5950 3425)(-5950 3375);
WIRE 16 -1 (-6125 3375)(-5950 3375);
WIRE 16 -1 (-5950 3375)(-5950 3325);
WIRE 16 -1 (-6125 3325)(-5950 3325);
WIRE 16 -1 (-5950 3325)(-5950 3275);
WIRE 16 -1 (-6125 3275)(-5950 3275);
WIRE 16 -1 (-5950 3275)(-5950 3225);
WIRE 16 -1 (-6125 3225)(-5950 3225);
WIRE 16 -1 (-5950 3225)(-5950 3175);
WIRE 16 -1 (-6125 3175)(-5950 3175);
WIRE 16 -1 (-5950 3175)(-5950 3125);
WIRE 16 -1 (-6125 3125)(-5950 3125);
WIRE 16 -1 (-5950 3125)(-5950 3075);
WIRE 16 -1 (-6125 3075)(-5950 3075);
WIRE 16 -1 (-5950 3075)(-5950 3025);
WIRE 16 -1 (-6125 3025)(-5950 3025);
WIRE 16 -1 (-5950 3025)(-5950 2975);
WIRE 16 -1 (-6125 2975)(-5950 2975);
WIRE 16 -1 (-5950 2975)(-5950 2925);
WIRE 16 -1 (-6125 2925)(-5950 2925);
WIRE 16 -1 (-5950 2925)(-5950 2875);
WIRE 16 -1 (-6125 2875)(-5950 2875);
WIRE 16 -1 (-5950 2875)(-5950 2825);
WIRE 16 -1 (-6125 2825)(-5950 2825);
WIRE 16 -1 (-5950 2825)(-5950 2775);
WIRE 16 -1 (-6125 2775)(-5950 2775);
WIRE 16 -1 (-5950 2775)(-5950 2725);
WIRE 16 -1 (-6125 2725)(-5950 2725);
WIRE 16 -1 (-5950 2725)(-5950 2675);
WIRE 16 -1 (-6125 2675)(-5950 2675);
WIRE 16 -1 (-5950 2675)(-5950 2625);
WIRE 16 -1 (-6125 2625)(-5950 2625);
WIRE 16 -1 (-5950 2625)(-5950 2575);
WIRE 16 -1 (-6125 2575)(-5950 2575);
WIRE 16 -1 (-5950 2575)(-5950 2525);
WIRE 16 -1 (-6125 2525)(-5950 2525);
WIRE 16 -1 (-5950 2525)(-5950 2475);
WIRE 16 -1 (-6125 2475)(-5950 2475);
WIRE 16 -1 (-5950 2475)(-5950 2425);
WIRE 16 -1 (-6125 2425)(-5950 2425);
WIRE 16 -1 (-5950 2425)(-5950 2375);
WIRE 16 -1 (-6125 2375)(-5950 2375);
WIRE 16 -1 (-5950 2375)(-5950 2325);
WIRE 16 -1 (-6125 2325)(-5950 2325);
WIRE 16 -1 (-5950 2325)(-5950 2275);
WIRE 16 -1 (-6125 2275)(-5950 2275);
WIRE 16 -1 (-5950 2275)(-5950 2225);
WIRE 16 -1 (-6125 2225)(-5950 2225);
WIRE 16 -1 (-5950 2225)(-5950 2175);
WIRE 16 -1 (-6125 2175)(-5950 2175);
WIRE 16 -1 (-5950 2175)(-5950 2125);
WIRE 16 -1 (-6125 2125)(-5950 2125);
WIRE 16 -1 (-5950 2125)(-5950 2075);
WIRE 16 -1 (-6125 2075)(-5950 2075);
WIRE 16 -1 (-5950 2075)(-5950 2025);
WIRE 16 -1 (-6125 2025)(-5950 2025);
WIRE 16 -1 (-5950 2025)(-5950 1975);
WIRE 16 -1 (-6125 1975)(-5950 1975);
WIRE 16 -1 (-5950 1975)(-5950 1925);
WIRE 16 -1 (-6125 1925)(-5950 1925);
WIRE 16 -1 (-5950 1925)(-5950 1875);
WIRE 16 -1 (-6125 1875)(-5950 1875);
WIRE 16 -1 (-5950 1875)(-5950 1825);
WIRE 16 -1 (-6125 1825)(-5950 1825);
WIRE 16 -1 (-5950 1825)(-5950 1775);
WIRE 16 -1 (-6125 1775)(-5950 1775);
WIRE 16 -1 (-5950 1775)(-5950 1725);
WIRE 16 -1 (-6125 1725)(-5950 1725);
WIRE 16 -1 (-5950 1725)(-5950 1675);
WIRE 16 -1 (-6125 1675)(-5950 1675);
WIRE 16 -1 (-5950 1675)(-5950 1625);
WIRE 16 -1 (-6125 1625)(-5950 1625);
WIRE 16 -1 (-5950 1625)(-5950 1575);
WIRE 16 -1 (-6125 1575)(-5950 1575);
WIRE 16 -1 (-5950 1575)(-5950 1525);
WIRE 16 -1 (-6125 1525)(-5950 1525);
WIRE 16 -1 (-5950 1525)(-5950 1475);
WIRE 16 -1 (-6125 1475)(-5950 1475);
WIRE 16 -1 (-5950 1475)(-5950 1425);
WIRE 16 -1 (-6125 1425)(-5950 1425);
WIRE 16 -1 (-5950 1425)(-5950 1375);
WIRE 16 -1 (-6125 1375)(-5950 1375);
WIRE 16 -1 (-5950 1375)(-5950 1325);
WIRE 16 -1 (-6125 1325)(-5950 1325);
WIRE 16 -1 (-5950 1325)(-5950 1275);
WIRE 16 -1 (-6125 1275)(-5950 1275);
WIRE 16 -1 (-5950 1275)(-5950 1225);
WIRE 16 -1 (-6125 1225)(-5950 1225);
WIRE 16 -1 (-5950 1225)(-5950 1175);
WIRE 16 -1 (-6125 1175)(-5950 1175);
WIRE 16 -1 (-5950 1175)(-5950 1125);
WIRE 16 -1 (-6125 1125)(-5950 1125);
WIRE 16 -1 (-5950 1125)(-5950 1075);
WIRE 16 -1 (-6125 1075)(-5950 1075);
WIRE 16 -1 (-5950 1075)(-5950 1025);
WIRE 16 -1 (-6125 1025)(-5950 1025);
WIRE 16 -1 (-5950 1025)(-5950 975);
WIRE 16 -1 (-6125 975)(-5950 975);
WIRE 16 -1 (-5950 975)(-5950 925);
WIRE 16 -1 (-6125 925)(-5950 925);
WIRE 16 -1 (-5950 925)(-5950 875);
WIRE 16 -1 (-6125 875)(-5950 875);
WIRE 16 -1 (-5950 875)(-5950 825);
WIRE 16 -1 (-6125 825)(-5950 825);
WIRE 16 -1 (-5950 825)(-5950 775);
WIRE 16 -1 (-6125 775)(-5950 775);
WIRE 16 -1 (-5950 775)(-5950 725);
WIRE 16 -1 (-6125 725)(-5950 725);
WIRE 16 -1 (-5950 725)(-5950 675);
WIRE 16 -1 (-6125 675)(-5950 675);
WIRE 16 -1 (-5950 675)(-5950 625);
WIRE 16 -1 (-6125 625)(-5950 625);
WIRE 16 -1 (-5950 625)(-5950 575);
WIRE 16 -1 (-6125 575)(-5950 575);
WIRE 16 -1 (-5950 575)(-5950 450);
WIRE 16 -1 (-625 4550)(-450 4550);
WIRE 16 -1 (-450 4550)(-450 4500);
WIRE 16 -1 (-625 4500)(-450 4500);
WIRE 16 -1 (-450 4500)(-450 4450);
WIRE 16 -1 (-625 4450)(-450 4450);
WIRE 16 -1 (-450 4450)(-450 4400);
WIRE 16 -1 (-625 4400)(-450 4400);
WIRE 16 -1 (-450 4400)(-450 4350);
WIRE 16 -1 (-625 4350)(-450 4350);
WIRE 16 -1 (-450 4350)(-450 4300);
WIRE 16 -1 (-625 4300)(-450 4300);
WIRE 16 -1 (-450 4300)(-450 4250);
WIRE 16 -1 (-625 4250)(-450 4250);
WIRE 16 -1 (-450 4250)(-450 4200);
WIRE 16 -1 (-625 4200)(-450 4200);
WIRE 16 -1 (-450 4200)(-450 4150);
WIRE 16 -1 (-625 4150)(-450 4150);
WIRE 16 -1 (-450 4150)(-450 4100);
WIRE 16 -1 (-625 4100)(-450 4100);
WIRE 16 -1 (-450 4100)(-450 4050);
WIRE 16 -1 (-625 4050)(-450 4050);
WIRE 16 -1 (-450 4050)(-450 4000);
WIRE 16 -1 (-625 4000)(-450 4000);
WIRE 16 -1 (-450 4000)(-450 3950);
WIRE 16 -1 (-625 3950)(-450 3950);
WIRE 16 -1 (-450 3950)(-450 3900);
WIRE 16 -1 (-625 3900)(-450 3900);
WIRE 16 -1 (-450 3900)(-450 3850);
WIRE 16 -1 (-625 3850)(-450 3850);
WIRE 16 -1 (-450 3850)(-450 3800);
WIRE 16 -1 (-625 3800)(-450 3800);
WIRE 16 -1 (-450 3800)(-450 3750);
WIRE 16 -1 (-625 3750)(-450 3750);
WIRE 16 -1 (-450 3750)(-450 3700);
WIRE 16 -1 (-625 3700)(-450 3700);
WIRE 16 -1 (-450 3700)(-450 3650);
WIRE 16 -1 (-625 3650)(-450 3650);
WIRE 16 -1 (-450 3650)(-450 3600);
WIRE 16 -1 (-625 3600)(-450 3600);
WIRE 16 -1 (-450 3600)(-450 3550);
WIRE 16 -1 (-625 3550)(-450 3550);
WIRE 16 -1 (-450 3550)(-450 3500);
WIRE 16 -1 (-625 3500)(-450 3500);
WIRE 16 -1 (-450 3500)(-450 3450);
WIRE 16 -1 (-625 3450)(-450 3450);
WIRE 16 -1 (-450 3450)(-450 3400);
WIRE 16 -1 (-625 3400)(-450 3400);
WIRE 16 -1 (-450 3400)(-450 3350);
WIRE 16 -1 (-625 3350)(-450 3350);
WIRE 16 -1 (-450 3350)(-450 3300);
WIRE 16 -1 (-625 3300)(-450 3300);
WIRE 16 -1 (-450 3300)(-450 3250);
WIRE 16 -1 (-625 3250)(-450 3250);
WIRE 16 -1 (-450 3250)(-450 3200);
WIRE 16 -1 (-625 3200)(-450 3200);
WIRE 16 -1 (-450 3200)(-450 3150);
WIRE 16 -1 (-625 3150)(-450 3150);
WIRE 16 -1 (-450 3150)(-450 3100);
WIRE 16 -1 (-625 3100)(-450 3100);
WIRE 16 -1 (-450 3100)(-450 3050);
WIRE 16 -1 (-625 3050)(-450 3050);
WIRE 16 -1 (-450 3050)(-450 3000);
WIRE 16 -1 (-625 3000)(-450 3000);
WIRE 16 -1 (-450 3000)(-450 2950);
WIRE 16 -1 (-625 2950)(-450 2950);
WIRE 16 -1 (-450 2950)(-450 2900);
WIRE 16 -1 (-625 2900)(-450 2900);
WIRE 16 -1 (-450 2900)(-450 2850);
WIRE 16 -1 (-625 2850)(-450 2850);
WIRE 16 -1 (-450 2850)(-450 2800);
WIRE 16 -1 (-625 2800)(-450 2800);
WIRE 16 -1 (-450 2800)(-450 2750);
WIRE 16 -1 (-625 2750)(-450 2750);
WIRE 16 -1 (-450 2750)(-450 2700);
WIRE 16 -1 (-625 2700)(-450 2700);
WIRE 16 -1 (-450 2700)(-450 2650);
WIRE 16 -1 (-625 2650)(-450 2650);
WIRE 16 -1 (-450 2650)(-450 2600);
WIRE 16 -1 (-625 2600)(-450 2600);
WIRE 16 -1 (-450 2600)(-450 2550);
WIRE 16 -1 (-625 2550)(-450 2550);
WIRE 16 -1 (-450 2550)(-450 2500);
WIRE 16 -1 (-625 2500)(-450 2500);
WIRE 16 -1 (-450 2500)(-450 2450);
WIRE 16 -1 (-625 2450)(-450 2450);
WIRE 16 -1 (-450 2450)(-450 2400);
WIRE 16 -1 (-625 2400)(-450 2400);
WIRE 16 -1 (-450 2400)(-450 2350);
WIRE 16 -1 (-625 2350)(-450 2350);
WIRE 16 -1 (-450 2350)(-450 2300);
WIRE 16 -1 (-625 2300)(-450 2300);
WIRE 16 -1 (-450 2300)(-450 2250);
WIRE 16 -1 (-625 2250)(-450 2250);
WIRE 16 -1 (-450 2250)(-450 2200);
WIRE 16 -1 (-625 2200)(-450 2200);
WIRE 16 -1 (-450 2200)(-450 2150);
WIRE 16 -1 (-625 2150)(-450 2150);
WIRE 16 -1 (-450 2150)(-450 2100);
WIRE 16 -1 (-625 2100)(-450 2100);
WIRE 16 -1 (-450 2100)(-450 2050);
WIRE 16 -1 (-625 2050)(-450 2050);
WIRE 16 -1 (-450 2050)(-450 2000);
WIRE 16 -1 (-625 2000)(-450 2000);
WIRE 16 -1 (-450 2000)(-450 1950);
WIRE 16 -1 (-625 1950)(-450 1950);
WIRE 16 -1 (-450 1900)(-450 1950);
WIRE 16 -1 (-625 1900)(-450 1900);
WIRE 16 -1 (-450 1750)(-450 1900);
WIRE 16 -1 (-7475 4525)(-7325 4525);
WIRE 16 -1 (-7475 4525)(-7475 4475);
WIRE 16 -1 (-7325 4475)(-7475 4475);
WIRE 16 -1 (-7475 4475)(-7475 4425);
WIRE 16 -1 (-7325 4425)(-7475 4425);
WIRE 16 -1 (-7475 4425)(-7475 4375);
WIRE 16 -1 (-7325 4375)(-7475 4375);
WIRE 16 -1 (-7475 4375)(-7475 4325);
WIRE 16 -1 (-7325 4325)(-7475 4325);
WIRE 16 -1 (-7475 4325)(-7475 4275);
WIRE 16 -1 (-7325 4275)(-7475 4275);
WIRE 16 -1 (-7475 4275)(-7475 4225);
WIRE 16 -1 (-7325 4225)(-7475 4225);
WIRE 16 -1 (-7475 4225)(-7475 4175);
WIRE 16 -1 (-7325 4175)(-7475 4175);
WIRE 16 -1 (-7475 4175)(-7475 4125);
WIRE 16 -1 (-7325 4125)(-7475 4125);
WIRE 16 -1 (-7475 4125)(-7475 4075);
WIRE 16 -1 (-7325 4075)(-7475 4075);
WIRE 16 -1 (-7475 4075)(-7475 4025);
WIRE 16 -1 (-7325 4025)(-7475 4025);
WIRE 16 -1 (-7475 4025)(-7475 3975);
WIRE 16 -1 (-7325 3975)(-7475 3975);
WIRE 16 -1 (-7475 3975)(-7475 3925);
WIRE 16 -1 (-7325 3925)(-7475 3925);
WIRE 16 -1 (-7475 3925)(-7475 3875);
WIRE 16 -1 (-7325 3875)(-7475 3875);
WIRE 16 -1 (-7475 3875)(-7475 3825);
WIRE 16 -1 (-7325 3825)(-7475 3825);
WIRE 16 -1 (-7475 3825)(-7475 3775);
WIRE 16 -1 (-7325 3775)(-7475 3775);
WIRE 16 -1 (-7475 3775)(-7475 3725);
WIRE 16 -1 (-7325 3725)(-7475 3725);
WIRE 16 -1 (-7475 3725)(-7475 3675);
WIRE 16 -1 (-7325 3675)(-7475 3675);
WIRE 16 -1 (-7475 3675)(-7475 3625);
WIRE 16 -1 (-7325 3625)(-7475 3625);
WIRE 16 -1 (-7475 3625)(-7475 3575);
WIRE 16 -1 (-7325 3575)(-7475 3575);
WIRE 16 -1 (-7475 3575)(-7475 3525);
WIRE 16 -1 (-7325 3525)(-7475 3525);
WIRE 16 -1 (-7475 3525)(-7475 3475);
WIRE 16 -1 (-7325 3475)(-7475 3475);
WIRE 16 -1 (-7475 3475)(-7475 3425);
WIRE 16 -1 (-7325 3425)(-7475 3425);
WIRE 16 -1 (-7475 3425)(-7475 3375);
WIRE 16 -1 (-7325 3375)(-7475 3375);
WIRE 16 -1 (-7475 3375)(-7475 3325);
WIRE 16 -1 (-7325 3325)(-7475 3325);
WIRE 16 -1 (-7475 3325)(-7475 3275);
WIRE 16 -1 (-7325 3275)(-7475 3275);
WIRE 16 -1 (-7475 3275)(-7475 3225);
WIRE 16 -1 (-7325 3225)(-7475 3225);
WIRE 16 -1 (-7475 3225)(-7475 3175);
WIRE 16 -1 (-7325 3175)(-7475 3175);
WIRE 16 -1 (-7475 3175)(-7475 3125);
WIRE 16 -1 (-7325 3125)(-7475 3125);
WIRE 16 -1 (-7475 3125)(-7475 3075);
WIRE 16 -1 (-7325 3075)(-7475 3075);
WIRE 16 -1 (-7475 3075)(-7475 3025);
WIRE 16 -1 (-7325 3025)(-7475 3025);
WIRE 16 -1 (-7475 3025)(-7475 2975);
WIRE 16 -1 (-7325 2975)(-7475 2975);
WIRE 16 -1 (-7475 2975)(-7475 2925);
WIRE 16 -1 (-7325 2925)(-7475 2925);
WIRE 16 -1 (-7475 2925)(-7475 2875);
WIRE 16 -1 (-7325 2875)(-7475 2875);
WIRE 16 -1 (-7475 2875)(-7475 2825);
WIRE 16 -1 (-7325 2825)(-7475 2825);
WIRE 16 -1 (-7475 2825)(-7475 2775);
WIRE 16 -1 (-7325 2775)(-7475 2775);
WIRE 16 -1 (-7475 2775)(-7475 2725);
WIRE 16 -1 (-7325 2725)(-7475 2725);
WIRE 16 -1 (-7475 2725)(-7475 2675);
WIRE 16 -1 (-7325 2675)(-7475 2675);
WIRE 16 -1 (-7475 2675)(-7475 2625);
WIRE 16 -1 (-7325 2625)(-7475 2625);
WIRE 16 -1 (-7475 2625)(-7475 2575);
WIRE 16 -1 (-7325 2575)(-7475 2575);
WIRE 16 -1 (-7475 2575)(-7475 2525);
WIRE 16 -1 (-7325 2525)(-7475 2525);
WIRE 16 -1 (-7475 2525)(-7475 2475);
WIRE 16 -1 (-7325 2475)(-7475 2475);
WIRE 16 -1 (-7475 2475)(-7475 2425);
WIRE 16 -1 (-7325 2425)(-7475 2425);
WIRE 16 -1 (-7475 2425)(-7475 2375);
WIRE 16 -1 (-7325 2375)(-7475 2375);
WIRE 16 -1 (-7475 2375)(-7475 2325);
WIRE 16 -1 (-7325 2325)(-7475 2325);
WIRE 16 -1 (-7475 2325)(-7475 2275);
WIRE 16 -1 (-7325 2275)(-7475 2275);
WIRE 16 -1 (-7475 2275)(-7475 2225);
WIRE 16 -1 (-7325 2225)(-7475 2225);
WIRE 16 -1 (-7475 2225)(-7475 2175);
WIRE 16 -1 (-7325 2175)(-7475 2175);
WIRE 16 -1 (-7475 2175)(-7475 2125);
WIRE 16 -1 (-7325 2125)(-7475 2125);
WIRE 16 -1 (-7475 2125)(-7475 2075);
WIRE 16 -1 (-7325 2075)(-7475 2075);
WIRE 16 -1 (-7475 2075)(-7475 2025);
WIRE 16 -1 (-7325 2025)(-7475 2025);
WIRE 16 -1 (-7475 2025)(-7475 1975);
WIRE 16 -1 (-7325 1975)(-7475 1975);
WIRE 16 -1 (-7475 1975)(-7475 1925);
WIRE 16 -1 (-7325 1925)(-7475 1925);
WIRE 16 -1 (-7475 1925)(-7475 1875);
WIRE 16 -1 (-7325 1875)(-7475 1875);
WIRE 16 -1 (-7475 1875)(-7475 1825);
WIRE 16 -1 (-7325 1825)(-7475 1825);
WIRE 16 -1 (-7475 1825)(-7475 1775);
WIRE 16 -1 (-7325 1775)(-7475 1775);
WIRE 16 -1 (-7475 1775)(-7475 1725);
WIRE 16 -1 (-7325 1725)(-7475 1725);
WIRE 16 -1 (-7475 1725)(-7475 1675);
WIRE 16 -1 (-7325 1675)(-7475 1675);
WIRE 16 -1 (-7475 1675)(-7475 1625);
WIRE 16 -1 (-7325 1625)(-7475 1625);
WIRE 16 -1 (-7475 1625)(-7475 1575);
WIRE 16 -1 (-7325 1575)(-7475 1575);
WIRE 16 -1 (-7475 1575)(-7475 1525);
WIRE 16 -1 (-7325 1525)(-7475 1525);
WIRE 16 -1 (-7475 1525)(-7475 1475);
WIRE 16 -1 (-7325 1475)(-7475 1475);
WIRE 16 -1 (-7475 1475)(-7475 1425);
WIRE 16 -1 (-7325 1425)(-7475 1425);
WIRE 16 -1 (-7475 1425)(-7475 1375);
WIRE 16 -1 (-7325 1375)(-7475 1375);
WIRE 16 -1 (-7475 1375)(-7475 1325);
WIRE 16 -1 (-7325 1325)(-7475 1325);
WIRE 16 -1 (-7475 1325)(-7475 1275);
WIRE 16 -1 (-7325 1275)(-7475 1275);
WIRE 16 -1 (-7475 1275)(-7475 1225);
WIRE 16 -1 (-7325 1225)(-7475 1225);
WIRE 16 -1 (-7475 1225)(-7475 1175);
WIRE 16 -1 (-7325 1175)(-7475 1175);
WIRE 16 -1 (-7475 1175)(-7475 1125);
WIRE 16 -1 (-7325 1125)(-7475 1125);
WIRE 16 -1 (-7475 1125)(-7475 1075);
WIRE 16 -1 (-7325 1075)(-7475 1075);
WIRE 16 -1 (-7475 1075)(-7475 1025);
WIRE 16 -1 (-7325 1025)(-7475 1025);
WIRE 16 -1 (-7475 1025)(-7475 975);
WIRE 16 -1 (-7325 975)(-7475 975);
WIRE 16 -1 (-7475 975)(-7475 925);
WIRE 16 -1 (-7325 925)(-7475 925);
WIRE 16 -1 (-7475 925)(-7475 875);
WIRE 16 -1 (-7325 875)(-7475 875);
WIRE 16 -1 (-7475 875)(-7475 825);
WIRE 16 -1 (-7325 825)(-7475 825);
WIRE 16 -1 (-7475 825)(-7475 775);
WIRE 16 -1 (-7325 775)(-7475 775);
WIRE 16 -1 (-7475 775)(-7475 725);
WIRE 16 -1 (-7325 725)(-7475 725);
WIRE 16 -1 (-7475 725)(-7475 675);
WIRE 16 -1 (-7325 675)(-7475 675);
WIRE 16 -1 (-7475 675)(-7475 625);
WIRE 16 -1 (-7325 625)(-7475 625);
WIRE 16 -1 (-7475 625)(-7475 575);
WIRE 16 -1 (-7475 575)(-7325 575);
WIRE 16 -1 (-7475 575)(-7475 450);
DOT 1 (-1975 3000);
DOT 1 (-450 2300);
DOT 1 (-450 1900);
DOT 1 (-450 1950);
DOT 1 (-450 2000);
DOT 1 (-450 2050);
DOT 1 (-450 2100);
DOT 1 (-450 2200);
DOT 1 (-450 2250);
DOT 1 (-5675 1775);
DOT 1 (-5675 1575);
DOT 1 (-4150 1575);
DOT 1 (-2275 1575);
DOT 1 (-2275 2175);
DOT 1 (-1975 2100);
DOT 1 (-2275 2275);
DOT 1 (-5675 1875);
DOT 1 (-5950 2225);
DOT 1 (-5675 2025);
DOT 1 (-4150 4475);
DOT 1 (-7475 1625);
DOT 1 (-5675 3675);
DOT 1 (-5675 3075);
DOT 1 (-5950 4375);
DOT 1 (-4150 2625);
DOT 1 (-4150 2325);
DOT 1 (-5950 575);
DOT 1 (-5950 625);
DOT 1 (-5950 675);
DOT 1 (-5950 725);
DOT 1 (-5950 825);
DOT 1 (-5950 775);
DOT 1 (-5950 925);
DOT 1 (-5950 875);
DOT 1 (-5950 975);
DOT 1 (-5950 1075);
DOT 1 (-5950 1025);
DOT 1 (-5950 1225);
DOT 1 (-5950 1125);
DOT 1 (-5950 1275);
DOT 1 (-5950 1475);
DOT 1 (-5950 1425);
DOT 1 (-5950 1375);
DOT 1 (-5950 1525);
DOT 1 (-5950 1575);
DOT 1 (-5950 1625);
DOT 1 (-5950 1725);
DOT 1 (-5950 1675);
DOT 1 (-5950 1775);
DOT 1 (-5950 1825);
DOT 1 (-5950 1875);
DOT 1 (-5950 1975);
DOT 1 (-5950 1925);
DOT 1 (-5950 2075);
DOT 1 (-5950 2125);
DOT 1 (-5950 2025);
DOT 1 (-5950 2175);
DOT 1 (-5950 2325);
DOT 1 (-5950 2375);
DOT 1 (-5950 2275);
DOT 1 (-5950 2425);
DOT 1 (-5950 2475);
DOT 1 (-5950 2575);
DOT 1 (-5950 2625);
DOT 1 (-5950 2525);
DOT 1 (-5950 2675);
DOT 1 (-5950 2725);
DOT 1 (-5950 2775);
DOT 1 (-5950 2875);
DOT 1 (-5950 2825);
DOT 1 (-5950 2975);
DOT 1 (-5950 2925);
DOT 1 (-5950 3025);
DOT 1 (-5950 3125);
DOT 1 (-5950 3075);
DOT 1 (-5950 3275);
DOT 1 (-5950 3225);
DOT 1 (-5950 3175);
DOT 1 (-5950 3375);
DOT 1 (-5950 3325);
DOT 1 (-5950 3525);
DOT 1 (-5950 3475);
DOT 1 (-5950 3425);
DOT 1 (-5950 3625);
DOT 1 (-5950 3575);
DOT 1 (-5950 3675);
DOT 1 (-5950 3775);
DOT 1 (-5950 3725);
DOT 1 (-5950 3875);
DOT 1 (-5950 3925);
DOT 1 (-5950 4025);
DOT 1 (-5950 3975);
DOT 1 (-5950 4125);
DOT 1 (-5950 4075);
DOT 1 (-5950 4175);
DOT 1 (-5950 4275);
DOT 1 (-5950 4225);
DOT 1 (-5950 4425);
DOT 1 (-5950 4325);
DOT 1 (-5950 4475);
DOT 1 (-4150 575);
DOT 1 (-4150 625);
DOT 1 (-4150 675);
DOT 1 (-4150 725);
DOT 1 (-4150 825);
DOT 1 (-4150 775);
DOT 1 (-4150 925);
DOT 1 (-4150 875);
DOT 1 (-4150 975);
DOT 1 (-4150 1075);
DOT 1 (-4150 1025);
DOT 1 (-4150 1225);
DOT 1 (-4150 1175);
DOT 1 (-4150 1125);
DOT 1 (-4150 1275);
DOT 1 (-4150 1325);
DOT 1 (-4150 1475);
DOT 1 (-4150 1425);
DOT 1 (-4150 1375);
DOT 1 (-4150 1525);
DOT 1 (-4150 1625);
DOT 1 (-4150 1725);
DOT 1 (-4150 1675);
DOT 1 (-4150 1775);
DOT 1 (-4150 1825);
DOT 1 (-4150 1875);
DOT 1 (-4150 1975);
DOT 1 (-4150 1925);
DOT 1 (-4150 2075);
DOT 1 (-4150 2125);
DOT 1 (-4150 2025);
DOT 1 (-4150 2175);
DOT 1 (-4150 2225);
DOT 1 (-4150 2375);
DOT 1 (-4150 2275);
DOT 1 (-4150 2425);
DOT 1 (-4150 2475);
DOT 1 (-4150 2575);
DOT 1 (-4150 2525);
DOT 1 (-4150 2675);
DOT 1 (-4150 2725);
DOT 1 (-4150 2775);
DOT 1 (-4150 2875);
DOT 1 (-4150 2825);
DOT 1 (-4150 2975);
DOT 1 (-4150 2925);
DOT 1 (-4150 3025);
DOT 1 (-4150 3125);
DOT 1 (-4150 3075);
DOT 1 (-4150 3275);
DOT 1 (-4150 3225);
DOT 1 (-4150 3175);
DOT 1 (-4150 3375);
DOT 1 (-4150 3325);
DOT 1 (-4150 3525);
DOT 1 (-4150 3475);
DOT 1 (-4150 3425);
DOT 1 (-4150 3625);
DOT 1 (-4150 3575);
DOT 1 (-4150 3675);
DOT 1 (-4150 3725);
DOT 1 (-4150 3875);
DOT 1 (-4150 3825);
DOT 1 (-4150 3925);
DOT 1 (-4150 4025);
DOT 1 (-4150 3975);
DOT 1 (-4150 4125);
DOT 1 (-4150 4075);
DOT 1 (-4150 4175);
DOT 1 (-4150 4275);
DOT 1 (-4150 4225);
DOT 1 (-4150 4375);
DOT 1 (-4150 4425);
DOT 1 (-4150 4325);
DOT 1 (-2275 575);
DOT 1 (-2275 625);
DOT 1 (-2275 675);
DOT 1 (-2275 725);
DOT 1 (-2275 825);
DOT 1 (-2275 775);
DOT 1 (-2275 925);
DOT 1 (-2275 875);
DOT 1 (-2275 1075);
DOT 1 (-2275 1025);
DOT 1 (-2275 1225);
DOT 1 (-2275 1175);
DOT 1 (-2275 1125);
DOT 1 (-2275 1275);
DOT 1 (-2275 1325);
DOT 1 (-2275 1475);
DOT 1 (-2275 1425);
DOT 1 (-2275 1375);
DOT 1 (-2275 1525);
DOT 1 (-2275 1625);
DOT 1 (-2275 1725);
DOT 1 (-2275 1675);
DOT 1 (-2275 1775);
DOT 1 (-2275 1825);
DOT 1 (-2275 1875);
DOT 1 (-2275 1975);
DOT 1 (-2275 1925);
DOT 1 (-2275 2075);
DOT 1 (-2275 2125);
DOT 1 (-2275 2025);
DOT 1 (-2275 2225);
DOT 1 (-2275 2325);
DOT 1 (-2275 2375);
DOT 1 (-2275 2425);
DOT 1 (-2275 2475);
DOT 1 (-2275 2575);
DOT 1 (-2275 2625);
DOT 1 (-2275 2525);
DOT 1 (-2275 2675);
DOT 1 (-2275 2725);
DOT 1 (-2275 2775);
DOT 1 (-2275 2875);
DOT 1 (-2275 2825);
DOT 1 (-2275 2975);
DOT 1 (-2275 2925);
DOT 1 (-2275 3025);
DOT 1 (-2275 3125);
DOT 1 (-2275 3075);
DOT 1 (-2275 3275);
DOT 1 (-2275 3225);
DOT 1 (-2275 3175);
DOT 1 (-2275 3375);
DOT 1 (-2275 3325);
DOT 1 (-2275 3525);
DOT 1 (-2275 3475);
DOT 1 (-2275 3425);
DOT 1 (-2275 3625);
DOT 1 (-2275 3575);
DOT 1 (-2275 3675);
DOT 1 (-2275 3775);
DOT 1 (-2275 3725);
DOT 1 (-2275 3875);
DOT 1 (-2275 3825);
DOT 1 (-2275 3925);
DOT 1 (-2275 4025);
DOT 1 (-2275 3975);
DOT 1 (-2275 4125);
DOT 1 (-2275 4075);
DOT 1 (-2275 4175);
DOT 1 (-2275 4275);
DOT 1 (-2275 4225);
DOT 1 (-2275 4425);
DOT 1 (-2275 4325);
DOT 1 (-2275 4475);
DOT 1 (-3775 4475);
DOT 1 (-3775 4425);
DOT 1 (-3775 4375);
DOT 1 (-3775 4325);
DOT 1 (-3775 4275);
DOT 1 (-3775 4225);
DOT 1 (-3775 4175);
DOT 1 (-3775 4125);
DOT 1 (-3775 4025);
DOT 1 (-3775 3975);
DOT 1 (-3775 3925);
DOT 1 (-3775 3875);
DOT 1 (-3775 3825);
DOT 1 (-3775 3775);
DOT 1 (-3775 3725);
DOT 1 (-3775 3675);
DOT 1 (-3775 3625);
DOT 1 (-3775 3575);
DOT 1 (-3775 3525);
DOT 1 (-3775 3475);
DOT 1 (-3775 3425);
DOT 1 (-3775 3375);
DOT 1 (-3775 3325);
DOT 1 (-3775 3275);
DOT 1 (-3775 3225);
DOT 1 (-3775 3175);
DOT 1 (-3775 3075);
DOT 1 (-3775 3125);
DOT 1 (-3775 3025);
DOT 1 (-3775 2975);
DOT 1 (-3775 2925);
DOT 1 (-3775 2875);
DOT 1 (-3775 2825);
DOT 1 (-3775 2775);
DOT 1 (-3775 2725);
DOT 1 (-3775 2675);
DOT 1 (-3775 2625);
DOT 1 (-3775 2575);
DOT 1 (-3775 2525);
DOT 1 (-3775 2475);
DOT 1 (-3775 2425);
DOT 1 (-3775 2375);
DOT 1 (-3775 2325);
DOT 1 (-3775 2275);
DOT 1 (-3775 2225);
DOT 1 (-3775 2175);
DOT 1 (-3775 2125);
DOT 1 (-3775 2075);
DOT 1 (-3775 2025);
DOT 1 (-3775 1975);
DOT 1 (-3775 1925);
DOT 1 (-3775 1875);
DOT 1 (-3775 1825);
DOT 1 (-3775 1775);
DOT 1 (-3775 1725);
DOT 1 (-3775 1675);
DOT 1 (-3775 1625);
DOT 1 (-3775 1525);
DOT 1 (-3775 1575);
DOT 1 (-3775 1475);
DOT 1 (-3775 1425);
DOT 1 (-3775 1375);
DOT 1 (-3775 1325);
DOT 1 (-3775 1275);
DOT 1 (-3775 1225);
DOT 1 (-3775 1175);
DOT 1 (-3775 1125);
DOT 1 (-3775 1075);
DOT 1 (-3775 1025);
DOT 1 (-3775 975);
DOT 1 (-3775 925);
DOT 1 (-3775 875);
DOT 1 (-3775 825);
DOT 1 (-3775 775);
DOT 1 (-3775 725);
DOT 1 (-3775 675);
DOT 1 (-3775 625);
DOT 1 (-3775 575);
DOT 1 (-5675 4475);
DOT 1 (-5675 4425);
DOT 1 (-5675 4375);
DOT 1 (-5675 4325);
DOT 1 (-5675 4275);
DOT 1 (-5675 4225);
DOT 1 (-5675 4175);
DOT 1 (-5675 4125);
DOT 1 (-5675 4075);
DOT 1 (-5675 4025);
DOT 1 (-5675 3975);
DOT 1 (-5675 3925);
DOT 1 (-5675 3875);
DOT 1 (-5675 3825);
DOT 1 (-5675 3775);
DOT 1 (-5675 3725);
DOT 1 (-5675 3625);
DOT 1 (-5675 3575);
DOT 1 (-5675 3525);
DOT 1 (-5675 3475);
DOT 1 (-5675 3425);
DOT 1 (-5675 3375);
DOT 1 (-5675 3325);
DOT 1 (-5675 3275);
DOT 1 (-5675 3225);
DOT 1 (-5675 3175);
DOT 1 (-5675 3125);
DOT 1 (-5675 3025);
DOT 1 (-5675 2975);
DOT 1 (-5675 2925);
DOT 1 (-5675 2875);
DOT 1 (-5675 2825);
DOT 1 (-5675 2775);
DOT 1 (-5675 2725);
DOT 1 (-5675 2675);
DOT 1 (-5675 2625);
DOT 1 (-5675 2575);
DOT 1 (-5675 2525);
DOT 1 (-5675 2475);
DOT 1 (-5675 2425);
DOT 1 (-5675 2375);
DOT 1 (-5675 2325);
DOT 1 (-5675 2275);
DOT 1 (-5675 2225);
DOT 1 (-5675 2175);
DOT 1 (-5675 2125);
DOT 1 (-5675 2075);
DOT 1 (-5675 1975);
DOT 1 (-5675 1925);
DOT 1 (-5675 1825);
DOT 1 (-5675 1625);
DOT 1 (-5675 1525);
DOT 1 (-5675 1475);
DOT 1 (-5675 1425);
DOT 1 (-5675 1375);
DOT 1 (-5675 1325);
DOT 1 (-5675 1275);
DOT 1 (-5675 1225);
DOT 1 (-5675 1075);
DOT 1 (-5675 1025);
DOT 1 (-5675 975);
DOT 1 (-5675 925);
DOT 1 (-5675 875);
DOT 1 (-5675 825);
DOT 1 (-5675 775);
DOT 1 (-5675 725);
DOT 1 (-5675 675);
DOT 1 (-5675 625);
DOT 1 (-5675 575);
DOT 1 (-7475 2225);
DOT 1 (-7475 1725);
DOT 1 (-7475 4475);
DOT 1 (-7475 4425);
DOT 1 (-7475 4375);
DOT 1 (-7475 4325);
DOT 1 (-7475 4275);
DOT 1 (-7475 4225);
DOT 1 (-7475 4175);
DOT 1 (-7475 4125);
DOT 1 (-7475 4075);
DOT 1 (-7475 4025);
DOT 1 (-7475 3975);
DOT 1 (-7475 3925);
DOT 1 (-7475 3875);
DOT 1 (-7475 3825);
DOT 1 (-7475 3775);
DOT 1 (-7475 3725);
DOT 1 (-7475 3675);
DOT 1 (-7475 3625);
DOT 1 (-7475 3575);
DOT 1 (-7475 3525);
DOT 1 (-7475 3475);
DOT 1 (-7475 3425);
DOT 1 (-7475 3375);
DOT 1 (-7475 3325);
DOT 1 (-7475 3275);
DOT 1 (-7475 3225);
DOT 1 (-7475 3175);
DOT 1 (-7475 3075);
DOT 1 (-7475 3125);
DOT 1 (-7475 3025);
DOT 1 (-7475 2975);
DOT 1 (-7475 2925);
DOT 1 (-7475 2875);
DOT 1 (-7475 2825);
DOT 1 (-7475 2775);
DOT 1 (-7475 2725);
DOT 1 (-7475 2675);
DOT 1 (-7475 2625);
DOT 1 (-7475 2575);
DOT 1 (-7475 2525);
DOT 1 (-7475 2475);
DOT 1 (-7475 2425);
DOT 1 (-7475 2375);
DOT 1 (-7475 2325);
DOT 1 (-7475 2275);
DOT 1 (-7475 2175);
DOT 1 (-7475 2125);
DOT 1 (-7475 2075);
DOT 1 (-7475 2025);
DOT 1 (-7475 1975);
DOT 1 (-7475 1925);
DOT 1 (-7475 1875);
DOT 1 (-7475 1825);
DOT 1 (-7475 1775);
DOT 1 (-7475 1675);
DOT 1 (-7475 1525);
DOT 1 (-7475 1575);
DOT 1 (-7475 1475);
DOT 1 (-7475 1425);
DOT 1 (-7475 1375);
DOT 1 (-7475 1325);
DOT 1 (-7475 1275);
DOT 1 (-7475 1225);
DOT 1 (-7475 1175);
DOT 1 (-7475 1125);
DOT 1 (-7475 1075);
DOT 1 (-7475 1025);
DOT 1 (-7475 975);
DOT 1 (-7475 925);
DOT 1 (-7475 875);
DOT 1 (-7475 825);
DOT 1 (-7475 775);
DOT 1 (-7475 725);
DOT 1 (-7475 675);
DOT 1 (-7475 625);
DOT 1 (-7475 575);
DOT 1 (-1975 4500);
DOT 1 (-1975 4450);
DOT 1 (-1975 4400);
DOT 1 (-1975 4350);
DOT 1 (-1975 4300);
DOT 1 (-1975 4250);
DOT 1 (-1975 4200);
DOT 1 (-1975 4150);
DOT 1 (-1975 4100);
DOT 1 (-1975 4050);
DOT 1 (-1975 3950);
DOT 1 (-1975 3900);
DOT 1 (-1975 3800);
DOT 1 (-1975 3750);
DOT 1 (-1975 3700);
DOT 1 (-1975 3650);
DOT 1 (-1975 3600);
DOT 1 (-1975 3550);
DOT 1 (-1975 3500);
DOT 1 (-1975 3450);
DOT 1 (-1975 3400);
DOT 1 (-1975 3350);
DOT 1 (-1975 3300);
DOT 1 (-1975 3250);
DOT 1 (-1975 3200);
DOT 1 (-1975 3150);
DOT 1 (-1975 3100);
DOT 1 (-1975 3050);
DOT 1 (-1975 2950);
DOT 1 (-1975 2900);
DOT 1 (-1975 2850);
DOT 1 (-1975 2800);
DOT 1 (-1975 2750);
DOT 1 (-1975 2700);
DOT 1 (-1975 2650);
DOT 1 (-1975 2600);
DOT 1 (-1975 2550);
DOT 1 (-1975 2500);
DOT 1 (-1975 2450);
DOT 1 (-1975 2400);
DOT 1 (-1975 2350);
DOT 1 (-1975 2300);
DOT 1 (-1975 2250);
DOT 1 (-1975 2200);
DOT 1 (-1975 2150);
DOT 1 (-1975 2050);
DOT 1 (-1975 2000);
DOT 1 (-1975 1950);
DOT 1 (-1975 1900);
DOT 1 (-1975 1850);
DOT 1 (-1975 1800);
DOT 1 (-1975 1750);
DOT 1 (-1975 1650);
DOT 1 (-1975 1600);
DOT 1 (-1975 1550);
DOT 1 (-1975 1500);
DOT 1 (-1975 1450);
DOT 1 (-1975 1400);
DOT 1 (-1975 1350);
DOT 1 (-1975 1300);
DOT 1 (-2275 975);
DOT 1 (-1975 1250);
DOT 1 (-1975 1200);
DOT 1 (-1975 1150);
DOT 1 (-1975 1100);
DOT 1 (-1975 1050);
DOT 1 (-1975 1000);
DOT 1 (-1975 950);
DOT 1 (-1975 900);
DOT 1 (-1975 850);
DOT 1 (-1975 800);
DOT 1 (-1975 750);
DOT 1 (-1975 700);
DOT 1 (-1975 650);
DOT 1 (-1975 3850);
DOT 1 (-1975 1700);
DOT 1 (-3775 4075);
DOT 1 (-5950 1175);
DOT 1 (-5675 1675);
DOT 1 (-5675 1725);
DOT 1 (-5675 1175);
DOT 1 (-5675 1125);
DOT 1 (-450 2150);
DOT 1 (-450 2350);
DOT 1 (-450 2400);
DOT 1 (-450 2450);
DOT 1 (-450 2500);
DOT 1 (-450 2550);
DOT 1 (-450 2600);
DOT 1 (-450 2700);
DOT 1 (-450 2750);
DOT 1 (-450 2800);
DOT 1 (-450 2850);
DOT 1 (-450 2900);
DOT 1 (-450 2950);
DOT 1 (-450 3000);
DOT 1 (-450 3050);
DOT 1 (-450 3100);
DOT 1 (-450 3150);
DOT 1 (-450 3200);
DOT 1 (-450 3250);
DOT 1 (-450 3300);
DOT 1 (-450 3350);
DOT 1 (-450 3400);
DOT 1 (-450 3450);
DOT 1 (-450 3500);
DOT 1 (-450 3550);
DOT 1 (-450 3600);
DOT 1 (-450 3650);
DOT 1 (-450 3700);
DOT 1 (-450 3750);
DOT 1 (-450 3800);
DOT 1 (-450 3850);
DOT 1 (-450 3900);
DOT 1 (-450 3950);
DOT 1 (-450 4000);
DOT 1 (-450 4050);
DOT 1 (-450 4100);
DOT 1 (-450 4150);
DOT 1 (-450 4200);
DOT 1 (-450 4250);
DOT 1 (-450 4300);
DOT 1 (-450 4350);
DOT 1 (-450 4400);
DOT 1 (-450 4450);
DOT 1 (-450 4500);
DOT 1 (-450 2650);
DOT 1 (-1975 4000);
DOT 1 (-2275 4375);
DOT 1 (-4150 3775);
DOT 1 (-5950 1325);
DOT 1 (-5950 3825);
DOT 1 (-1975 600);
QUIT
